G04 ================== begin FILE IDENTIFICATION RECORD ==================*
G04 Layout Name:  D:/<user>/Wistron_project/16316-1/gbr-0621/16316-1.brd*
G04 Film Name:    BMASK*
G04 File Format:  Gerber RS274X*
G04 File Origin:  Cadence Allegro 16.5-S056*
G04 Origin Date:  Wed Jun 21 09:31:31 2017*
G04 *
G04 Layer:  VIA CLASS/SOLDERMASK_BOTTOM*
G04 Layer:  PIN/SOLDERMASK_BOTTOM*
G04 Layer:  PACKAGE GEOMETRY/SOLDERMASK_BOTTOM*
G04 Layer:  DRAWING FORMAT/LAYER_PCB_STORY*
G04 Layer:  DRAWING FORMAT/LAYER_SOLDER_B*
G04 Layer:  BOARD GEOMETRY/SOLDERMASK_BOTTOM*
G04 *
G04 Offset:    (0.00 0.00)*
G04 Mirror:    No*
G04 Mode:      Positive*
G04 Rotation:  0*
G04 FullContactRelief:  No*
G04 UndefLineWidth:     6.00*
G04 ================== end FILE IDENTIFICATION RECORD ====================*
%FSLAX35Y35*MOIN*%
%IR0*IPPOS*OFA0.00000B0.00000*MIA0B0*SFA1.00000B1.00000*%
%AMMACRO41*
4,1,40,.011,.007,
.011,-.007,
.010939,-.007695,
.010759,-.008368,
.010464,-.009,
.010064,-.009571,
.009571,-.010064,
.009,-.010464,
.008368,-.010759,
.007695,-.010939,
.007,-.011,
-.007,-.011,
-.007695,-.010939,
-.008368,-.010759,
-.009,-.010464,
-.009571,-.010064,
-.010064,-.009571,
-.010464,-.009,
-.010759,-.008368,
-.010939,-.007695,
-.011,-.007,
-.011,.007,
-.010939,.007695,
-.010759,.008368,
-.010464,.009,
-.010064,.009571,
-.009571,.010064,
-.009,.010464,
-.008368,.010759,
-.007695,.010939,
-.007,.011,
.007,.011,
.007695,.010939,
.008368,.010759,
.009,.010464,
.009571,.010064,
.010064,.009571,
.010464,.009,
.010759,.008368,
.010939,.007695,
.011,.007,
0.0*
%
%ADD41MACRO41*%
%AMMACRO32*
4,1,40,-.017,-.013,
-.017,.013,
-.016939,.013695,
-.016759,.014368,
-.016464,.015,
-.016064,.015571,
-.015571,.016064,
-.015,.016464,
-.014368,.016759,
-.013695,.016939,
-.013,.017,
.013,.017,
.013695,.016939,
.014368,.016759,
.015,.016464,
.015571,.016064,
.016064,.015571,
.016464,.015,
.016759,.014368,
.016939,.013695,
.017,.013,
.017,-.013,
.016939,-.013695,
.016759,-.014368,
.016464,-.015,
.016064,-.015571,
.015571,-.016064,
.015,-.016464,
.014368,-.016759,
.013695,-.016939,
.013,-.017,
-.013,-.017,
-.013695,-.016939,
-.014368,-.016759,
-.015,-.016464,
-.015571,-.016064,
-.016064,-.015571,
-.016464,-.015,
-.016759,-.014368,
-.016939,-.013695,
-.017,-.013,
0.0*
%
%ADD32MACRO32*%
%AMMACRO25*
4,1,40,.013,-.017,
-.013,-.017,
-.013695,-.016939,
-.014368,-.016759,
-.015,-.016464,
-.015571,-.016064,
-.016064,-.015571,
-.016464,-.015,
-.016759,-.014368,
-.016939,-.013695,
-.017,-.013,
-.017,.013,
-.016939,.013695,
-.016759,.014368,
-.016464,.015,
-.016064,.015571,
-.015571,.016064,
-.015,.016464,
-.014368,.016759,
-.013695,.016939,
-.013,.017,
.013,.017,
.013695,.016939,
.014368,.016759,
.015,.016464,
.015571,.016064,
.016064,.015571,
.016464,.015,
.016759,.014368,
.016939,.013695,
.017,.013,
.017,-.013,
.016939,-.013695,
.016759,-.014368,
.016464,-.015,
.016064,-.015571,
.015571,-.016064,
.015,-.016464,
.014368,-.016759,
.013695,-.016939,
.013,-.017,
0.0*
%
%ADD25MACRO25*%
%ADD11C,.02*%
%ADD46C,.03*%
%AMMACRO49*
4,1,40,-.007,-.004,
-.007,.004,
-.00697,.004347,
-.006879,.004684,
-.006732,.005,
-.006532,.005286,
-.006286,.005532,
-.006,.005732,
-.005684,.005879,
-.005347,.00597,
-.005,.006,
.005,.006,
.005347,.00597,
.005684,.005879,
.006,.005732,
.006286,.005532,
.006532,.005286,
.006732,.005,
.006879,.004684,
.00697,.004347,
.007,.004,
.007,-.004,
.00697,-.004347,
.006879,-.004684,
.006732,-.005,
.006532,-.005286,
.006286,-.005532,
.006,-.005732,
.005684,-.005879,
.005347,-.00597,
.005,-.006,
-.005,-.006,
-.005347,-.00597,
-.005684,-.005879,
-.006,-.005732,
-.006286,-.005532,
-.006532,-.005286,
-.006732,-.005,
-.006879,-.004684,
-.00697,-.004347,
-.007,-.004,
0.0*
%
%ADD49MACRO49*%
%ADD19C,.042*%
%ADD13C,.024*%
%AMMACRO62*
4,1,40,-.004,.007,
.004,.007,
.004347,.00697,
.004684,.006879,
.005,.006732,
.005286,.006532,
.005532,.006286,
.005732,.006,
.005879,.005684,
.00597,.005347,
.006,.005,
.006,-.005,
.00597,-.005347,
.005879,-.005684,
.005732,-.006,
.005532,-.006286,
.005286,-.006532,
.005,-.006732,
.004684,-.006879,
.004347,-.00697,
.004,-.007,
-.004,-.007,
-.004347,-.00697,
-.004684,-.006879,
-.005,-.006732,
-.005286,-.006532,
-.005532,-.006286,
-.005732,-.006,
-.005879,-.005684,
-.00597,-.005347,
-.006,-.005,
-.006,.005,
-.00597,.005347,
-.005879,.005684,
-.005732,.006,
-.005532,.006286,
-.005286,.006532,
-.005,.006732,
-.004684,.006879,
-.004347,.00697,
-.004,.007,
0.0*
%
%ADD62MACRO62*%
%ADD12C,.08*%
%ADD57C,.028*%
%ADD64C,.029*%
%ADD20C,.048*%
%ADD17C,.094*%
%ADD10C,.086*%
%ADD60C,.087*%
%ADD15C,.078*%
%AMMACRO68*
4,1,40,.008,.014,
-.008,.014,
-.008695,.013939,
-.009368,.013759,
-.01,.013464,
-.010571,.013064,
-.011064,.012571,
-.011464,.012,
-.011759,.011368,
-.011939,.010695,
-.012,.01,
-.012,-.01,
-.011939,-.010695,
-.011759,-.011368,
-.011464,-.012,
-.011064,-.012571,
-.010571,-.013064,
-.01,-.013464,
-.009368,-.013759,
-.008695,-.013939,
-.008,-.014,
.008,-.014,
.008695,-.013939,
.009368,-.013759,
.01,-.013464,
.010571,-.013064,
.011064,-.012571,
.011464,-.012,
.011759,-.011368,
.011939,-.010695,
.012,-.01,
.012,.01,
.011939,.010695,
.011759,.011368,
.011464,.012,
.011064,.012571,
.010571,.013064,
.01,.013464,
.009368,.013759,
.008695,.013939,
.008,.014,
0.0*
%
%ADD68MACRO68*%
%AMMACRO65*
4,1,40,.0225,.007,
.022378,.008389,
.022018,.009736,
.021428,.011,
.020628,.012142,
.019642,.013128,
.0185,.013928,
.017236,.014518,
.015889,.014878,
.0145,.015,
-.0145,.015,
-.015889,.014878,
-.017236,.014518,
-.0185,.013928,
-.019642,.013128,
-.020628,.012142,
-.021428,.011,
-.022018,.009736,
-.022378,.008389,
-.0225,.007,
-.0225,-.007,
-.022378,-.008389,
-.022018,-.009736,
-.021428,-.011,
-.020628,-.012142,
-.019642,-.013128,
-.0185,-.013928,
-.017236,-.014518,
-.015889,-.014878,
-.0145,-.015,
.0145,-.015,
.015889,-.014878,
.017236,-.014518,
.0185,-.013928,
.019642,-.013128,
.020628,-.012142,
.021428,-.011,
.022018,-.009736,
.022378,-.008389,
.0225,-.007,
.0225,.007,
0.0*
%
%ADD65MACRO65*%
%ADD18C,.097*%
%AMMACRO71*
4,1,40,.007,-.0225,
.008389,-.022378,
.009736,-.022018,
.011,-.021428,
.012142,-.020628,
.013128,-.019642,
.013928,-.0185,
.014518,-.017236,
.014878,-.015889,
.015,-.0145,
.015,.0145,
.014878,.015889,
.014518,.017236,
.013928,.0185,
.013128,.019642,
.012142,.020628,
.011,.021428,
.009736,.022018,
.008389,.022378,
.007,.0225,
-.007,.0225,
-.008389,.022378,
-.009736,.022018,
-.011,.021428,
-.012142,.020628,
-.013128,.019642,
-.013928,.0185,
-.014518,.017236,
-.014878,.015889,
-.015,.0145,
-.015,-.0145,
-.014878,-.015889,
-.014518,-.017236,
-.013928,-.0185,
-.013128,-.019642,
-.012142,-.020628,
-.011,-.021428,
-.009736,-.022018,
-.008389,-.022378,
-.007,-.0225,
.007,-.0225,
0.0*
%
%ADD71MACRO71*%
%AMMACRO50*
4,1,40,.014,-.008,
.014,.008,
.013939,.008695,
.013759,.009368,
.013464,.01,
.013064,.010571,
.012571,.011064,
.012,.011464,
.011368,.011759,
.010695,.011939,
.01,.012,
-.01,.012,
-.010695,.011939,
-.011368,.011759,
-.012,.011464,
-.012571,.011064,
-.013064,.010571,
-.013464,.01,
-.013759,.009368,
-.013939,.008695,
-.014,.008,
-.014,-.008,
-.013939,-.008695,
-.013759,-.009368,
-.013464,-.01,
-.013064,-.010571,
-.012571,-.011064,
-.012,-.011464,
-.011368,-.011759,
-.010695,-.011939,
-.01,-.012,
.01,-.012,
.010695,-.011939,
.011368,-.011759,
.012,-.011464,
.012571,-.011064,
.013064,-.010571,
.013464,-.01,
.013759,-.009368,
.013939,-.008695,
.014,-.008,
0.0*
%
%ADD50MACRO50*%
%ADD16C,.099*%
%AMMACRO53*
4,1,40,.007,-.011,
-.007,-.011,
-.007695,-.010939,
-.008368,-.010759,
-.009,-.010464,
-.009571,-.010064,
-.010064,-.009571,
-.010464,-.009,
-.010759,-.008368,
-.010939,-.007695,
-.011,-.007,
-.011,.007,
-.010939,.007695,
-.010759,.008368,
-.010464,.009,
-.010064,.009571,
-.009571,.010064,
-.009,.010464,
-.008368,.010759,
-.007695,.010939,
-.007,.011,
.007,.011,
.007695,.010939,
.008368,.010759,
.009,.010464,
.009571,.010064,
.010064,.009571,
.010464,.009,
.010759,.008368,
.010939,.007695,
.011,.007,
.011,-.007,
.010939,-.007695,
.010759,-.008368,
.010464,-.009,
.010064,-.009571,
.009571,-.010064,
.009,-.010464,
.008368,-.010759,
.007695,-.010939,
.007,-.011,
0.0*
%
%ADD53MACRO53*%
%AMMACRO38*
4,1,40,-.011,-.007,
-.011,.007,
-.010939,.007695,
-.010759,.008368,
-.010464,.009,
-.010064,.009571,
-.009571,.010064,
-.009,.010464,
-.008368,.010759,
-.007695,.010939,
-.007,.011,
.007,.011,
.007695,.010939,
.008368,.010759,
.009,.010464,
.009571,.010064,
.010064,.009571,
.010464,.009,
.010759,.008368,
.010939,.007695,
.011,.007,
.011,-.007,
.010939,-.007695,
.010759,-.008368,
.010464,-.009,
.010064,-.009571,
.009571,-.010064,
.009,-.010464,
.008368,-.010759,
.007695,-.010939,
.007,-.011,
-.007,-.011,
-.007695,-.010939,
-.008368,-.010759,
-.009,-.010464,
-.009571,-.010064,
-.010064,-.009571,
-.010464,-.009,
-.010759,-.008368,
-.010939,-.007695,
-.011,-.007,
0.0*
%
%ADD38MACRO38*%
%AMMACRO22*
4,1,40,-.012,-.008,
-.012,.008,
-.011939,.008695,
-.011759,.009368,
-.011464,.01,
-.011064,.010571,
-.010571,.011064,
-.01,.011464,
-.009368,.011759,
-.008695,.011939,
-.008,.012,
.008,.012,
.008695,.011939,
.009368,.011759,
.01,.011464,
.010571,.011064,
.011064,.010571,
.011464,.01,
.011759,.009368,
.011939,.008695,
.012,.008,
.012,-.008,
.011939,-.008695,
.011759,-.009368,
.011464,-.01,
.011064,-.010571,
.010571,-.011064,
.01,-.011464,
.009368,-.011759,
.008695,-.011939,
.008,-.012,
-.008,-.012,
-.008695,-.011939,
-.009368,-.011759,
-.01,-.011464,
-.010571,-.011064,
-.011064,-.010571,
-.011464,-.01,
-.011759,-.009368,
-.011939,-.008695,
-.012,-.008,
0.0*
%
%ADD22MACRO22*%
%AMMACRO43*
4,1,40,-.008,.012,
.008,.012,
.008695,.011939,
.009368,.011759,
.01,.011464,
.010571,.011064,
.011064,.010571,
.011464,.01,
.011759,.009368,
.011939,.008695,
.012,.008,
.012,-.008,
.011939,-.008695,
.011759,-.009368,
.011464,-.01,
.011064,-.010571,
.010571,-.011064,
.01,-.011464,
.009368,-.011759,
.008695,-.011939,
.008,-.012,
-.008,-.012,
-.008695,-.011939,
-.009368,-.011759,
-.01,-.011464,
-.010571,-.011064,
-.011064,-.010571,
-.011464,-.01,
-.011759,-.009368,
-.011939,-.008695,
-.012,-.008,
-.012,.008,
-.011939,.008695,
-.011759,.009368,
-.011464,.01,
-.011064,.010571,
-.010571,.011064,
-.01,.011464,
-.009368,.011759,
-.008695,.011939,
-.008,.012,
0.0*
%
%ADD43MACRO43*%
%AMMACRO35*
4,1,40,-.013,.017,
.013,.017,
.013695,.016939,
.014368,.016759,
.015,.016464,
.015571,.016064,
.016064,.015571,
.016464,.015,
.016759,.014368,
.016939,.013695,
.017,.013,
.017,-.013,
.016939,-.013695,
.016759,-.014368,
.016464,-.015,
.016064,-.015571,
.015571,-.016064,
.015,-.016464,
.014368,-.016759,
.013695,-.016939,
.013,-.017,
-.013,-.017,
-.013695,-.016939,
-.014368,-.016759,
-.015,-.016464,
-.015571,-.016064,
-.016064,-.015571,
-.016464,-.015,
-.016759,-.014368,
-.016939,-.013695,
-.017,-.013,
-.017,.013,
-.016939,.013695,
-.016759,.014368,
-.016464,.015,
-.016064,.015571,
-.015571,.016064,
-.015,.016464,
-.014368,.016759,
-.013695,.016939,
-.013,.017,
0.0*
%
%ADD35MACRO35*%
%AMMACRO29*
4,1,40,.017,.013,
.017,-.013,
.016939,-.013695,
.016759,-.014368,
.016464,-.015,
.016064,-.015571,
.015571,-.016064,
.015,-.016464,
.014368,-.016759,
.013695,-.016939,
.013,-.017,
-.013,-.017,
-.013695,-.016939,
-.014368,-.016759,
-.015,-.016464,
-.015571,-.016064,
-.016064,-.015571,
-.016464,-.015,
-.016759,-.014368,
-.016939,-.013695,
-.017,-.013,
-.017,.013,
-.016939,.013695,
-.016759,.014368,
-.016464,.015,
-.016064,.015571,
-.015571,.016064,
-.015,.016464,
-.014368,.016759,
-.013695,.016939,
-.013,.017,
.013,.017,
.013695,.016939,
.014368,.016759,
.015,.016464,
.015571,.016064,
.016064,.015571,
.016464,.015,
.016759,.014368,
.016939,.013695,
.017,.013,
0.0*
%
%ADD29MACRO29*%
%AMMACRO73*
4,1,6,-.005,.0135,
-.005,.0065,
-.025,-.0135,
.025,-.0135,
.005,.0065,
.005,.0135,
-.005,.0135,
0.0*
%
%ADD73MACRO73*%
%AMMACRO54*
4,1,40,.007,-.011,
-.007,-.011,
-.007695,-.010939,
-.008368,-.010759,
-.009,-.010464,
-.009571,-.010064,
-.010064,-.009571,
-.010464,-.009,
-.010759,-.008368,
-.010939,-.007695,
-.011,-.007,
-.011,.007,
-.010939,.007695,
-.010759,.008368,
-.010464,.009,
-.010064,.009571,
-.009571,.010064,
-.009,.010464,
-.008368,.010759,
-.007695,.010939,
-.007,.011,
.007,.011,
.007695,.010939,
.008368,.010759,
.009,.010464,
.009571,.010064,
.010064,.009571,
.010464,.009,
.010759,.008368,
.010939,.007695,
.011,.007,
.011,-.007,
.010939,-.007695,
.010759,-.008368,
.010464,-.009,
.010064,-.009571,
.009571,-.010064,
.009,-.010464,
.008368,-.010759,
.007695,-.010939,
.007,-.011,
0.0*
%
%ADD54MACRO54*%
%AMMACRO39*
4,1,40,-.011,-.007,
-.011,.007,
-.010939,.007695,
-.010759,.008368,
-.010464,.009,
-.010064,.009571,
-.009571,.010064,
-.009,.010464,
-.008368,.010759,
-.007695,.010939,
-.007,.011,
.007,.011,
.007695,.010939,
.008368,.010759,
.009,.010464,
.009571,.010064,
.010064,.009571,
.010464,.009,
.010759,.008368,
.010939,.007695,
.011,.007,
.011,-.007,
.010939,-.007695,
.010759,-.008368,
.010464,-.009,
.010064,-.009571,
.009571,-.010064,
.009,-.010464,
.008368,-.010759,
.007695,-.010939,
.007,-.011,
-.007,-.011,
-.007695,-.010939,
-.008368,-.010759,
-.009,-.010464,
-.009571,-.010064,
-.010064,-.009571,
-.010464,-.009,
-.010759,-.008368,
-.010939,-.007695,
-.011,-.007,
0.0*
%
%ADD39MACRO39*%
%AMMACRO21*
4,1,40,-.012,-.008,
-.012,.008,
-.011939,.008695,
-.011759,.009368,
-.011464,.01,
-.011064,.010571,
-.010571,.011064,
-.01,.011464,
-.009368,.011759,
-.008695,.011939,
-.008,.012,
.008,.012,
.008695,.011939,
.009368,.011759,
.01,.011464,
.010571,.011064,
.011064,.010571,
.011464,.01,
.011759,.009368,
.011939,.008695,
.012,.008,
.012,-.008,
.011939,-.008695,
.011759,-.009368,
.011464,-.01,
.011064,-.010571,
.010571,-.011064,
.01,-.011464,
.009368,-.011759,
.008695,-.011939,
.008,-.012,
-.008,-.012,
-.008695,-.011939,
-.009368,-.011759,
-.01,-.011464,
-.010571,-.011064,
-.011064,-.010571,
-.011464,-.01,
-.011759,-.009368,
-.011939,-.008695,
-.012,-.008,
0.0*
%
%ADD21MACRO21*%
%AMMACRO42*
4,1,40,-.008,.012,
.008,.012,
.008695,.011939,
.009368,.011759,
.01,.011464,
.010571,.011064,
.011064,.010571,
.011464,.01,
.011759,.009368,
.011939,.008695,
.012,.008,
.012,-.008,
.011939,-.008695,
.011759,-.009368,
.011464,-.01,
.011064,-.010571,
.010571,-.011064,
.01,-.011464,
.009368,-.011759,
.008695,-.011939,
.008,-.012,
-.008,-.012,
-.008695,-.011939,
-.009368,-.011759,
-.01,-.011464,
-.010571,-.011064,
-.011064,-.010571,
-.011464,-.01,
-.011759,-.009368,
-.011939,-.008695,
-.012,-.008,
-.012,.008,
-.011939,.008695,
-.011759,.009368,
-.011464,.01,
-.011064,.010571,
-.010571,.011064,
-.01,.011464,
-.009368,.011759,
-.008695,.011939,
-.008,.012,
0.0*
%
%ADD42MACRO42*%
%AMMACRO36*
4,1,40,-.013,.017,
.013,.017,
.013695,.016939,
.014368,.016759,
.015,.016464,
.015571,.016064,
.016064,.015571,
.016464,.015,
.016759,.014368,
.016939,.013695,
.017,.013,
.017,-.013,
.016939,-.013695,
.016759,-.014368,
.016464,-.015,
.016064,-.015571,
.015571,-.016064,
.015,-.016464,
.014368,-.016759,
.013695,-.016939,
.013,-.017,
-.013,-.017,
-.013695,-.016939,
-.014368,-.016759,
-.015,-.016464,
-.015571,-.016064,
-.016064,-.015571,
-.016464,-.015,
-.016759,-.014368,
-.016939,-.013695,
-.017,-.013,
-.017,.013,
-.016939,.013695,
-.016759,.014368,
-.016464,.015,
-.016064,.015571,
-.015571,.016064,
-.015,.016464,
-.014368,.016759,
-.013695,.016939,
-.013,.017,
0.0*
%
%ADD36MACRO36*%
%AMMACRO30*
4,1,40,.017,.013,
.017,-.013,
.016939,-.013695,
.016759,-.014368,
.016464,-.015,
.016064,-.015571,
.015571,-.016064,
.015,-.016464,
.014368,-.016759,
.013695,-.016939,
.013,-.017,
-.013,-.017,
-.013695,-.016939,
-.014368,-.016759,
-.015,-.016464,
-.015571,-.016064,
-.016064,-.015571,
-.016464,-.015,
-.016759,-.014368,
-.016939,-.013695,
-.017,-.013,
-.017,.013,
-.016939,.013695,
-.016759,.014368,
-.016464,.015,
-.016064,.015571,
-.015571,.016064,
-.015,.016464,
-.014368,.016759,
-.013695,.016939,
-.013,.017,
.013,.017,
.013695,.016939,
.014368,.016759,
.015,.016464,
.015571,.016064,
.016064,.015571,
.016464,.015,
.016759,.014368,
.016939,.013695,
.017,.013,
0.0*
%
%ADD30MACRO30*%
%ADD77R,.022X.04*%
%ADD75R,.06X.012*%
%ADD58R,.023X.04*%
%ADD44R,.012X.06*%
%ADD59R,.016X.032*%
%ADD26R,.05X.08*%
%AMMACRO61*
4,1,40,.007,.004,
.007,-.004,
.00697,-.004347,
.006879,-.004684,
.006732,-.005,
.006532,-.005286,
.006286,-.005532,
.006,-.005732,
.005684,-.005879,
.005347,-.00597,
.005,-.006,
-.005,-.006,
-.005347,-.00597,
-.005684,-.005879,
-.006,-.005732,
-.006286,-.005532,
-.006532,-.005286,
-.006732,-.005,
-.006879,-.004684,
-.00697,-.004347,
-.007,-.004,
-.007,.004,
-.00697,.004347,
-.006879,.004684,
-.006732,.005,
-.006532,.005286,
-.006286,.005532,
-.006,.005732,
-.005684,.005879,
-.005347,.00597,
-.005,.006,
.005,.006,
.005347,.00597,
.005684,.005879,
.006,.005732,
.006286,.005532,
.006532,.005286,
.006732,.005,
.006879,.004684,
.00697,.004347,
.007,.004,
0.0*
%
%ADD61MACRO61*%
%AMMACRO47*
4,1,40,.004,-.007,
-.004,-.007,
-.004347,-.00697,
-.004684,-.006879,
-.005,-.006732,
-.005286,-.006532,
-.005532,-.006286,
-.005732,-.006,
-.005879,-.005684,
-.00597,-.005347,
-.006,-.005,
-.006,.005,
-.00597,.005347,
-.005879,.005684,
-.005732,.006,
-.005532,.006286,
-.005286,.006532,
-.005,.006732,
-.004684,.006879,
-.004347,.00697,
-.004,.007,
.004,.007,
.004347,.00697,
.004684,.006879,
.005,.006732,
.005286,.006532,
.005532,.006286,
.005732,.006,
.005879,.005684,
.00597,.005347,
.006,.005,
.006,-.005,
.00597,-.005347,
.005879,-.005684,
.005732,-.006,
.005532,-.006286,
.005286,-.006532,
.005,-.006732,
.004684,-.006879,
.004347,-.00697,
.004,-.007,
0.0*
%
%ADD47MACRO47*%
%ADD72R,.05X.065*%
%ADD37R,.065X.05*%
%ADD76R,.065X.025*%
%ADD69R,.048X.016*%
%ADD67R,.025X.065*%
%ADD23R,.045X.055*%
%ADD52R,.055X.045*%
%ADD48C,.119*%
%AMMACRO14*
4,1,25,-.26575,.30715,
-.209725,.333219,
-.150024,.349164,
-.088461,.3545,
-.026908,.349064,
.032767,.333022,
.08875,.306861,
.139339,.271377,
.182998,.227647,
.2184,.177,
.244469,.120975,
.260414,.061274,
.26575,-.000289,
.260314,-.061842,
.244272,-.121517,
.218111,-.1775,
.182627,-.228089,
.138897,-.271748,
.08825,-.30715,
.032225,-.333219,
-.027476,-.349164,
-.089039,-.3545,
-.150592,-.349064,
-.210267,-.333022,
-.26575,-.30715,
-.26575,.30715,
0.0*
%
%ADD14MACRO14*%
%AMMACRO78*
4,1,25,.26575,.30715,
.209725,.333219,
.150024,.349164,
.088461,.3545,
.026908,.349064,
-.032767,.333022,
-.08875,.306861,
-.139339,.271377,
-.182998,.227647,
-.2184,.177,
-.244469,.120975,
-.260414,.061274,
-.26575,-.000289,
-.260314,-.061842,
-.244272,-.121517,
-.218111,-.1775,
-.182627,-.228089,
-.138897,-.271748,
-.08825,-.30715,
-.032225,-.333219,
.027476,-.349164,
.089039,-.3545,
.150592,-.349064,
.210267,-.333022,
.26575,-.30715,
.26575,.30715,
0.0*
%
%ADD78MACRO78*%
%ADD45C,.375*%
%AMMACRO70*
4,1,40,-.007,.0225,
-.008389,.022378,
-.009736,.022018,
-.011,.021428,
-.012142,.020628,
-.013128,.019642,
-.013928,.0185,
-.014518,.017236,
-.014878,.015889,
-.015,.0145,
-.015,-.0145,
-.014878,-.015889,
-.014518,-.017236,
-.013928,-.0185,
-.013128,-.019642,
-.012142,-.020628,
-.011,-.021428,
-.009736,-.022018,
-.008389,-.022378,
-.007,-.0225,
.007,-.0225,
.008389,-.022378,
.009736,-.022018,
.011,-.021428,
.012142,-.020628,
.013128,-.019642,
.013928,-.0185,
.014518,-.017236,
.014878,-.015889,
.015,-.0145,
.015,.0145,
.014878,.015889,
.014518,.017236,
.013928,.0185,
.013128,.019642,
.012142,.020628,
.011,.021428,
.009736,.022018,
.008389,.022378,
.007,.0225,
-.007,.0225,
0.0*
%
%ADD70MACRO70*%
%AMMACRO66*
4,1,40,-.0225,-.007,
-.022378,-.008389,
-.022018,-.009736,
-.021428,-.011,
-.020628,-.012142,
-.019642,-.013128,
-.0185,-.013928,
-.017236,-.014518,
-.015889,-.014878,
-.0145,-.015,
.0145,-.015,
.015889,-.014878,
.017236,-.014518,
.0185,-.013928,
.019642,-.013128,
.020628,-.012142,
.021428,-.011,
.022018,-.009736,
.022378,-.008389,
.0225,-.007,
.0225,.007,
.022378,.008389,
.022018,.009736,
.021428,.011,
.020628,.012142,
.019642,.013128,
.0185,.013928,
.017236,.014518,
.015889,.014878,
.0145,.015,
-.0145,.015,
-.015889,.014878,
-.017236,.014518,
-.0185,.013928,
-.019642,.013128,
-.020628,.012142,
-.021428,.011,
-.022018,.009736,
-.022378,.008389,
-.0225,.007,
-.0225,-.007,
0.0*
%
%ADD66MACRO66*%
%AMMACRO63*
4,1,40,-.008,-.014,
.008,-.014,
.008695,-.013939,
.009368,-.013759,
.01,-.013464,
.010571,-.013064,
.011064,-.012571,
.011464,-.012,
.011759,-.011368,
.011939,-.010695,
.012,-.01,
.012,.01,
.011939,.010695,
.011759,.011368,
.011464,.012,
.011064,.012571,
.010571,.013064,
.01,.013464,
.009368,.013759,
.008695,.013939,
.008,.014,
-.008,.014,
-.008695,.013939,
-.009368,.013759,
-.01,.013464,
-.010571,.013064,
-.011064,.012571,
-.011464,.012,
-.011759,.011368,
-.011939,.010695,
-.012,.01,
-.012,-.01,
-.011939,-.010695,
-.011759,-.011368,
-.011464,-.012,
-.011064,-.012571,
-.010571,-.013064,
-.01,-.013464,
-.009368,-.013759,
-.008695,-.013939,
-.008,-.014,
0.0*
%
%ADD63MACRO63*%
%AMMACRO51*
4,1,40,-.014,.008,
-.014,-.008,
-.013939,-.008695,
-.013759,-.009368,
-.013464,-.01,
-.013064,-.010571,
-.012571,-.011064,
-.012,-.011464,
-.011368,-.011759,
-.010695,-.011939,
-.01,-.012,
.01,-.012,
.010695,-.011939,
.011368,-.011759,
.012,-.011464,
.012571,-.011064,
.013064,-.010571,
.013464,-.01,
.013759,-.009368,
.013939,-.008695,
.014,-.008,
.014,.008,
.013939,.008695,
.013759,.009368,
.013464,.01,
.013064,.010571,
.012571,.011064,
.012,.011464,
.011368,.011759,
.010695,.011939,
.01,.012,
-.01,.012,
-.010695,.011939,
-.011368,.011759,
-.012,.011464,
-.012571,.011064,
-.013064,.010571,
-.013464,.01,
-.013759,.009368,
-.013939,.008695,
-.014,.008,
0.0*
%
%ADD51MACRO51*%
%AMMACRO55*
4,1,40,-.007,.011,
.007,.011,
.007695,.010939,
.008368,.010759,
.009,.010464,
.009571,.010064,
.010064,.009571,
.010464,.009,
.010759,.008368,
.010939,.007695,
.011,.007,
.011,-.007,
.010939,-.007695,
.010759,-.008368,
.010464,-.009,
.010064,-.009571,
.009571,-.010064,
.009,-.010464,
.008368,-.010759,
.007695,-.010939,
.007,-.011,
-.007,-.011,
-.007695,-.010939,
-.008368,-.010759,
-.009,-.010464,
-.009571,-.010064,
-.010064,-.009571,
-.010464,-.009,
-.010759,-.008368,
-.010939,-.007695,
-.011,-.007,
-.011,.007,
-.010939,.007695,
-.010759,.008368,
-.010464,.009,
-.010064,.009571,
-.009571,.010064,
-.009,.010464,
-.008368,.010759,
-.007695,.010939,
-.007,.011,
0.0*
%
%ADD55MACRO55*%
%AMMACRO34*
4,1,40,.008,-.012,
-.008,-.012,
-.008695,-.011939,
-.009368,-.011759,
-.01,-.011464,
-.010571,-.011064,
-.011064,-.010571,
-.011464,-.01,
-.011759,-.009368,
-.011939,-.008695,
-.012,-.008,
-.012,.008,
-.011939,.008695,
-.011759,.009368,
-.011464,.01,
-.011064,.010571,
-.010571,.011064,
-.01,.011464,
-.009368,.011759,
-.008695,.011939,
-.008,.012,
.008,.012,
.008695,.011939,
.009368,.011759,
.01,.011464,
.010571,.011064,
.011064,.010571,
.011464,.01,
.011759,.009368,
.011939,.008695,
.012,.008,
.012,-.008,
.011939,-.008695,
.011759,-.009368,
.011464,-.01,
.011064,-.010571,
.010571,-.011064,
.01,-.011464,
.009368,-.011759,
.008695,-.011939,
.008,-.012,
0.0*
%
%ADD34MACRO34*%
%AMMACRO28*
4,1,40,.012,.008,
.012,-.008,
.011939,-.008695,
.011759,-.009368,
.011464,-.01,
.011064,-.010571,
.010571,-.011064,
.01,-.011464,
.009368,-.011759,
.008695,-.011939,
.008,-.012,
-.008,-.012,
-.008695,-.011939,
-.009368,-.011759,
-.01,-.011464,
-.010571,-.011064,
-.011064,-.010571,
-.011464,-.01,
-.011759,-.009368,
-.011939,-.008695,
-.012,-.008,
-.012,.008,
-.011939,.008695,
-.011759,.009368,
-.011464,.01,
-.011064,.010571,
-.010571,.011064,
-.01,.011464,
-.009368,.011759,
-.008695,.011939,
-.008,.012,
.008,.012,
.008695,.011939,
.009368,.011759,
.01,.011464,
.010571,.011064,
.011064,.010571,
.011464,.01,
.011759,.009368,
.011939,.008695,
.012,.008,
0.0*
%
%ADD28MACRO28*%
%AMMACRO40*
4,1,40,.011,.007,
.011,-.007,
.010939,-.007695,
.010759,-.008368,
.010464,-.009,
.010064,-.009571,
.009571,-.010064,
.009,-.010464,
.008368,-.010759,
.007695,-.010939,
.007,-.011,
-.007,-.011,
-.007695,-.010939,
-.008368,-.010759,
-.009,-.010464,
-.009571,-.010064,
-.010064,-.009571,
-.010464,-.009,
-.010759,-.008368,
-.010939,-.007695,
-.011,-.007,
-.011,.007,
-.010939,.007695,
-.010759,.008368,
-.010464,.009,
-.010064,.009571,
-.009571,.010064,
-.009,.010464,
-.008368,.010759,
-.007695,.010939,
-.007,.011,
.007,.011,
.007695,.010939,
.008368,.010759,
.009,.010464,
.009571,.010064,
.010064,.009571,
.010464,.009,
.010759,.008368,
.010939,.007695,
.011,.007,
0.0*
%
%ADD40MACRO40*%
%AMMACRO74*
4,1,6,-.025,.0135,
-.005,-.0065,
-.005,-.0135,
.005,-.0135,
.005,-.0065,
.025,.0135,
-.025,.0135,
0.0*
%
%ADD74MACRO74*%
%AMMACRO31*
4,1,40,-.017,-.013,
-.017,.013,
-.016939,.013695,
-.016759,.014368,
-.016464,.015,
-.016064,.015571,
-.015571,.016064,
-.015,.016464,
-.014368,.016759,
-.013695,.016939,
-.013,.017,
.013,.017,
.013695,.016939,
.014368,.016759,
.015,.016464,
.015571,.016064,
.016064,.015571,
.016464,.015,
.016759,.014368,
.016939,.013695,
.017,.013,
.017,-.013,
.016939,-.013695,
.016759,-.014368,
.016464,-.015,
.016064,-.015571,
.015571,-.016064,
.015,-.016464,
.014368,-.016759,
.013695,-.016939,
.013,-.017,
-.013,-.017,
-.013695,-.016939,
-.014368,-.016759,
-.015,-.016464,
-.015571,-.016064,
-.016064,-.015571,
-.016464,-.015,
-.016759,-.014368,
-.016939,-.013695,
-.017,-.013,
0.0*
%
%ADD31MACRO31*%
%AMMACRO24*
4,1,40,.013,-.017,
-.013,-.017,
-.013695,-.016939,
-.014368,-.016759,
-.015,-.016464,
-.015571,-.016064,
-.016064,-.015571,
-.016464,-.015,
-.016759,-.014368,
-.016939,-.013695,
-.017,-.013,
-.017,.013,
-.016939,.013695,
-.016759,.014368,
-.016464,.015,
-.016064,.015571,
-.015571,.016064,
-.015,.016464,
-.014368,.016759,
-.013695,.016939,
-.013,.017,
.013,.017,
.013695,.016939,
.014368,.016759,
.015,.016464,
.015571,.016064,
.016064,.015571,
.016464,.015,
.016759,.014368,
.016939,.013695,
.017,.013,
.017,-.013,
.016939,-.013695,
.016759,-.014368,
.016464,-.015,
.016064,-.015571,
.015571,-.016064,
.015,-.016464,
.014368,-.016759,
.013695,-.016939,
.013,-.017,
0.0*
%
%ADD24MACRO24*%
%AMMACRO56*
4,1,40,-.007,.011,
.007,.011,
.007695,.010939,
.008368,.010759,
.009,.010464,
.009571,.010064,
.010064,.009571,
.010464,.009,
.010759,.008368,
.010939,.007695,
.011,.007,
.011,-.007,
.010939,-.007695,
.010759,-.008368,
.010464,-.009,
.010064,-.009571,
.009571,-.010064,
.009,-.010464,
.008368,-.010759,
.007695,-.010939,
.007,-.011,
-.007,-.011,
-.007695,-.010939,
-.008368,-.010759,
-.009,-.010464,
-.009571,-.010064,
-.010064,-.009571,
-.010464,-.009,
-.010759,-.008368,
-.010939,-.007695,
-.011,-.007,
-.011,.007,
-.010939,.007695,
-.010759,.008368,
-.010464,.009,
-.010064,.009571,
-.009571,.010064,
-.009,.010464,
-.008368,.010759,
-.007695,.010939,
-.007,.011,
0.0*
%
%ADD56MACRO56*%
%AMMACRO33*
4,1,40,.008,-.012,
-.008,-.012,
-.008695,-.011939,
-.009368,-.011759,
-.01,-.011464,
-.010571,-.011064,
-.011064,-.010571,
-.011464,-.01,
-.011759,-.009368,
-.011939,-.008695,
-.012,-.008,
-.012,.008,
-.011939,.008695,
-.011759,.009368,
-.011464,.01,
-.011064,.010571,
-.010571,.011064,
-.01,.011464,
-.009368,.011759,
-.008695,.011939,
-.008,.012,
.008,.012,
.008695,.011939,
.009368,.011759,
.01,.011464,
.010571,.011064,
.011064,.010571,
.011464,.01,
.011759,.009368,
.011939,.008695,
.012,.008,
.012,-.008,
.011939,-.008695,
.011759,-.009368,
.011464,-.01,
.011064,-.010571,
.010571,-.011064,
.01,-.011464,
.009368,-.011759,
.008695,-.011939,
.008,-.012,
0.0*
%
%ADD33MACRO33*%
%AMMACRO27*
4,1,40,.012,.008,
.012,-.008,
.011939,-.008695,
.011759,-.009368,
.011464,-.01,
.011064,-.010571,
.010571,-.011064,
.01,-.011464,
.009368,-.011759,
.008695,-.011939,
.008,-.012,
-.008,-.012,
-.008695,-.011939,
-.009368,-.011759,
-.01,-.011464,
-.010571,-.011064,
-.011064,-.010571,
-.011464,-.01,
-.011759,-.009368,
-.011939,-.008695,
-.012,-.008,
-.012,.008,
-.011939,.008695,
-.011759,.009368,
-.011464,.01,
-.011064,.010571,
-.010571,.011064,
-.01,.011464,
-.009368,.011759,
-.008695,.011939,
-.008,.012,
.008,.012,
.008695,.011939,
.009368,.011759,
.01,.011464,
.010571,.011064,
.011064,.010571,
.011464,.01,
.011759,.009368,
.011939,.008695,
.012,.008,
0.0*
%
%ADD27MACRO27*%
%ADD79C,.006*%
G75*
%LPD*%
G75*
G36*
G01X169038Y469636D02*
Y461636D01*
X155038D01*
Y469636D01*
X169038D01*
G37*
G36*
G01X164538Y447136D02*
X159538D01*
Y439136D01*
X164538D01*
Y447136D01*
G37*
G54D10*
X15812Y-86244D03*
X27058Y25484D03*
X81539Y542850D03*
X411652Y539991D03*
X812711Y-86834D03*
X798456Y26432D03*
G54D20*
X158267Y25708D03*
X145669D03*
X158267Y47362D03*
X145669D03*
X158267Y53267D03*
Y41456D03*
Y31614D03*
Y19803D03*
X145669D03*
Y31614D03*
Y41456D03*
Y53267D03*
G54D11*
G01X-34018Y-300855D02*
G02I-12000J0D01*
G01X-39168D02*
G02I-6850J0D01*
G01X-30018D02*
X-62018D01*
G01X-30018Y-316855D02*
Y-396855D01*
G01D02*
X1320682D01*
G01X-30018Y-352355D02*
X1320682D01*
G01X-46018Y-316855D02*
Y-284855D01*
G01X-30018Y-316855D02*
X1320682D01*
G01X533182D02*
Y-396855D01*
G01X670682Y-316855D02*
Y-396855D01*
G01X785682Y-316855D02*
Y-396855D01*
G01X953182Y-316855D02*
Y-396855D01*
G01X1123182Y-316855D02*
Y-396855D01*
G01X1320682Y-316855D02*
Y-396855D01*
G01X1348682Y-300855D02*
G02I-12000J0D01*
G01X1343532D02*
G02I-6850J0D01*
G01X1336682Y-316855D02*
Y-284855D01*
G01X1352682Y-300855D02*
X1320682D01*
X15364Y5500D03*
X10364D03*
X5500Y10384D03*
Y15384D03*
Y20384D03*
Y25384D03*
Y30384D03*
Y35384D03*
Y40384D03*
Y45384D03*
Y50384D03*
Y55384D03*
Y60384D03*
Y65384D03*
Y70384D03*
Y75384D03*
Y80384D03*
Y85384D03*
Y90384D03*
Y95384D03*
Y100384D03*
Y105384D03*
Y110384D03*
Y115384D03*
Y120384D03*
Y125384D03*
Y130384D03*
Y135384D03*
Y140384D03*
Y145384D03*
Y150384D03*
Y155384D03*
Y160384D03*
Y165384D03*
Y170384D03*
Y175384D03*
Y180384D03*
Y185384D03*
Y190384D03*
Y195384D03*
Y200384D03*
Y205384D03*
Y210384D03*
Y215384D03*
Y220384D03*
Y225384D03*
Y230384D03*
Y235384D03*
Y240384D03*
Y245384D03*
Y250384D03*
Y255384D03*
Y260384D03*
Y265384D03*
Y270384D03*
Y275384D03*
Y280384D03*
Y285384D03*
Y290384D03*
Y295384D03*
Y300384D03*
Y305384D03*
Y310384D03*
Y315384D03*
Y320384D03*
Y325384D03*
Y330384D03*
Y335384D03*
Y340384D03*
Y345384D03*
Y350384D03*
Y355384D03*
Y360384D03*
Y365384D03*
Y370384D03*
Y375384D03*
Y380384D03*
Y385384D03*
Y390384D03*
Y395384D03*
Y400384D03*
Y405384D03*
Y410384D03*
Y415384D03*
Y420384D03*
Y425384D03*
Y430384D03*
Y435384D03*
Y440384D03*
Y445384D03*
Y450384D03*
Y455384D03*
Y460384D03*
Y465384D03*
Y470384D03*
Y475384D03*
Y480384D03*
Y485384D03*
Y530384D03*
Y525384D03*
Y520384D03*
Y515384D03*
Y510384D03*
Y505384D03*
Y490384D03*
Y495384D03*
Y500384D03*
Y535384D03*
Y540384D03*
Y545384D03*
Y550384D03*
Y555384D03*
Y560384D03*
X10266Y565366D03*
X15266D03*
X75364Y5500D03*
X70364D03*
X65364D03*
X60364D03*
X55364D03*
X50364D03*
X45364D03*
X40364D03*
X35364D03*
X30364D03*
X25364D03*
X20364D03*
X75119Y111166D03*
X20266Y565366D03*
X25266D03*
X30266D03*
X35266D03*
X40266D03*
X45266D03*
X50266D03*
X55266D03*
X60266D03*
X65266D03*
X70266D03*
X75266D03*
X95364Y5500D03*
X90364D03*
X85364D03*
X80364D03*
X105619Y111166D03*
X81119D03*
X87619D03*
X93619D03*
X99619D03*
X128580Y170810D03*
X122984Y170984D03*
X123200Y175800D03*
X125741Y166309D03*
X128459Y175658D03*
X140000Y204950D03*
X94080Y448470D03*
X80266Y565366D03*
X85266D03*
X90266D03*
X95266D03*
X100266D03*
X105266D03*
X110266D03*
X115266D03*
X120266D03*
X125266D03*
X130266D03*
X135266D03*
X200364Y5500D03*
X195364D03*
X190364D03*
X185364D03*
X180364D03*
X175364D03*
X170364D03*
X192830Y170500D03*
X197630D03*
X192830Y165700D03*
X197630D03*
X192830Y160900D03*
X197630D03*
X170900Y160500D03*
X151500D03*
X156300D03*
X161100D03*
X165900D03*
X198557Y153196D03*
X191900Y196100D03*
X196900D03*
X201700D03*
X196900Y200900D03*
X191900D03*
X196900Y205700D03*
X191900D03*
X196900Y210500D03*
X191900D03*
X201700Y205700D03*
Y200900D03*
X151500Y205000D03*
X156300D03*
X161100D03*
X165900D03*
X170900D03*
X178450Y203150D03*
X144800Y204950D03*
X177850Y324800D03*
X174995Y353588D03*
Y358388D03*
X165195D03*
X169995D03*
Y353588D03*
X197718Y350937D03*
Y355859D03*
X157650Y418100D03*
X160400Y422900D03*
X160550Y414100D03*
X177468Y417900D03*
X142865Y424021D03*
X143608Y415900D03*
X158067Y378857D03*
X160400Y427700D03*
Y432500D03*
X176311Y445493D03*
X176423Y440472D03*
X177421Y432909D03*
X177532Y426134D03*
X145392Y445207D03*
X145456Y440338D03*
X142991Y430900D03*
X200266Y565366D03*
X195266D03*
X190266D03*
X185266D03*
X180266D03*
X175266D03*
X140266D03*
X145266D03*
X150266D03*
X155266D03*
X160266D03*
X165266D03*
X170266D03*
X260364Y5500D03*
X255364D03*
X250364D03*
X245364D03*
X240364D03*
X235364D03*
X230364D03*
X225364D03*
X220364D03*
X215364D03*
X210364D03*
X205364D03*
X222700Y149300D03*
X227500D03*
X222700Y144500D03*
X227500D03*
X222700Y139700D03*
X227500D03*
X222700Y158900D03*
X227500D03*
X222700Y154100D03*
X227500D03*
X202430Y170500D03*
Y165700D03*
Y160900D03*
X253600Y139500D03*
Y134700D03*
X251800Y153600D03*
Y144000D03*
Y148800D03*
X258400Y134700D03*
Y139500D03*
X263200Y134700D03*
Y139500D03*
X222800Y204600D03*
X227600D03*
X222800Y219000D03*
X227600D03*
X222800Y214200D03*
X227600D03*
X222800Y209400D03*
X227600D03*
X222490Y235373D03*
X227290D03*
X222246Y229952D03*
X227046D03*
X222800Y223800D03*
X227600D03*
X253600Y230500D03*
Y225700D03*
Y220900D03*
X258400Y230500D03*
Y225700D03*
Y220900D03*
X263200Y230500D03*
Y225700D03*
Y220900D03*
X222460Y240264D03*
X227260D03*
X249204Y244103D03*
X254300Y357732D03*
X222818Y364806D03*
X222909Y371864D03*
X223000Y378246D03*
X246700Y418600D03*
X209052Y470198D03*
X213700Y448450D03*
X208900D03*
X203000Y451300D03*
X204252Y470198D03*
X204364Y478917D03*
X209164D03*
X212589Y494694D03*
X220589D03*
X216589Y489694D03*
X208589D03*
X224589D03*
X205266Y565366D03*
X210266D03*
X215266D03*
X220266D03*
X225266D03*
X230266D03*
X235266D03*
X240266D03*
X245266D03*
X250266D03*
X255266D03*
X260266D03*
X325364Y5500D03*
X320364D03*
X315364D03*
X310364D03*
X305364D03*
X300364D03*
X295364D03*
X290364D03*
X285364D03*
X280364D03*
X275364D03*
X270364D03*
X265364D03*
X295960Y148987D03*
Y154387D03*
X308907Y171800D03*
Y166400D03*
Y161000D03*
X287000Y117600D03*
Y125000D03*
X285500Y130400D03*
X290300D03*
X287300Y173000D03*
X292100D03*
X295650Y169554D03*
X295100Y130400D03*
X272800Y168000D03*
Y172800D03*
Y134700D03*
X268000Y165962D03*
X268064Y171792D03*
X268000Y158700D03*
Y153900D03*
Y134700D03*
Y139500D03*
Y144300D03*
Y149100D03*
X296200Y195900D03*
Y190500D03*
X308907Y215200D03*
Y220600D03*
Y226000D03*
Y231400D03*
Y236800D03*
Y209800D03*
Y188200D03*
Y199000D03*
Y204400D03*
Y177200D03*
Y193600D03*
Y182800D03*
X296400Y237950D03*
Y232550D03*
X295801Y210294D03*
X292600Y214500D03*
X287800D03*
X272800Y177600D03*
X268064Y184062D03*
X268000Y235300D03*
Y230500D03*
Y225700D03*
Y220900D03*
Y216000D03*
Y211200D03*
X268118Y191305D03*
X268000Y206400D03*
Y196800D03*
Y201600D03*
Y178062D03*
X308907Y242200D03*
X295879Y255540D03*
X291079D03*
X286279D03*
X266404Y249707D03*
X268000Y244900D03*
Y240100D03*
X276070Y395357D03*
X265266Y565366D03*
X270266D03*
X275266D03*
X280266D03*
X285266D03*
X290266D03*
X295266D03*
X300266D03*
X305266D03*
X310266D03*
X315266D03*
X320266D03*
X325266D03*
X330364Y5500D03*
X346700Y296333D03*
Y291533D03*
X350586Y495815D03*
X355523Y495025D03*
X360461Y494236D03*
X365398Y493446D03*
X370335Y492656D03*
X375272Y491866D03*
X380210Y491077D03*
X385169Y490563D03*
X329156Y545492D03*
Y540492D03*
Y535492D03*
Y530492D03*
Y525492D03*
Y520492D03*
Y515492D03*
Y560492D03*
Y555492D03*
Y550492D03*
X405169Y490563D03*
X410169D03*
X415169D03*
X420169D03*
X425169D03*
X430169D03*
X435169D03*
X440169D03*
X445146Y490850D03*
X450083Y491640D03*
X390169Y490563D03*
X395169D03*
X400169D03*
X505500Y464400D03*
Y469200D03*
Y474000D03*
X509500Y450800D03*
Y446000D03*
Y441200D03*
X469832Y494799D03*
X474769Y495589D03*
X455020Y492430D03*
X459958Y493219D03*
X464895Y494009D03*
X497636Y515532D03*
Y520532D03*
Y525532D03*
Y530532D03*
Y535532D03*
Y540532D03*
Y545532D03*
Y550532D03*
Y555532D03*
Y560532D03*
X502550Y565366D03*
X507550D03*
X512550D03*
X570234Y298026D03*
X572634Y293526D03*
X571300Y414800D03*
X567200Y407700D03*
X572062Y384378D03*
X527742Y425481D03*
X522942D03*
X518142D03*
X527742Y432481D03*
X522942D03*
X518142D03*
X529500Y471500D03*
X551400Y437800D03*
X545900D03*
X539800Y437900D03*
X517550Y565366D03*
X522550D03*
X527550D03*
X532550D03*
X537550D03*
X542550D03*
X547550D03*
X552550D03*
X557550D03*
X562550D03*
X567550D03*
X572550D03*
X591446Y6545D03*
X596446D03*
X601446D03*
X606446D03*
X611446D03*
X616446D03*
X621446D03*
X636446D03*
X631446D03*
X626446D03*
X576797Y113877D03*
X582554Y116361D03*
X575134Y298026D03*
X577534Y293526D03*
X580034Y298026D03*
X580900Y414800D03*
X576100D03*
X632150Y389100D03*
X576862Y384378D03*
X581087Y379569D03*
X576287D03*
X581692Y384378D03*
X628113Y428617D03*
X623313D03*
X618513D03*
X613713D03*
X605534Y480027D03*
X635000Y427784D03*
X619600Y446100D03*
X629200D03*
X624400D03*
X577550Y565366D03*
X582550D03*
X587550D03*
X592550D03*
X597550D03*
X602550D03*
X607550D03*
X612550D03*
X617550D03*
X622550D03*
X627550D03*
X632550D03*
X641446Y6545D03*
X646446D03*
X651446D03*
X696446D03*
X691446D03*
X661446D03*
X656446D03*
X686446D03*
X681446D03*
X676446D03*
X671446D03*
X666446D03*
X655964Y52248D03*
X675136Y268500D03*
X637705Y298765D03*
X642705D03*
X659977Y323082D03*
X664731Y324099D03*
X660115Y351977D03*
Y356777D03*
X664731Y343299D03*
X655500Y360000D03*
X660115Y361577D03*
X664731Y338499D03*
Y333699D03*
Y328899D03*
X659977Y342282D03*
Y332682D03*
Y347082D03*
Y337482D03*
Y327882D03*
X696900Y337800D03*
X697500Y358200D03*
X637705Y303765D03*
X642705D03*
X674700Y306300D03*
X679500D03*
Y311100D03*
X674700D03*
X679500Y315900D03*
X674700D03*
X665520Y307707D03*
Y312507D03*
X654642D03*
X654488Y317417D03*
X660100Y307500D03*
X654642Y307707D03*
X665478Y317527D03*
X684400Y400100D03*
X637550Y389050D03*
X655532Y425245D03*
X658032Y420245D03*
X653032D03*
X653200Y408800D03*
X694950Y477850D03*
Y473050D03*
X688500Y484400D03*
X675700Y468000D03*
Y463500D03*
X675400Y472300D03*
X659000Y428900D03*
X652200Y429100D03*
X639120Y462230D03*
X688500Y488600D03*
X637550Y565366D03*
X642550D03*
X647550D03*
X652550D03*
X657550D03*
X662550D03*
X667550D03*
X672550D03*
X677550D03*
X682550D03*
X687550D03*
X692550D03*
X697550D03*
X701446Y6545D03*
X742200Y340800D03*
Y345600D03*
X737400Y340800D03*
Y345600D03*
X732600Y331200D03*
Y336000D03*
Y340800D03*
Y355200D03*
Y350400D03*
Y345600D03*
X701100Y315900D03*
X705900D03*
X701100Y311100D03*
X705900D03*
Y306300D03*
X701100D03*
X714600Y338900D03*
Y348500D03*
Y343700D03*
X709800Y348500D03*
Y343700D03*
X706500Y337800D03*
X701700D03*
X707100Y358200D03*
X702300D03*
X704115Y414466D03*
Y409666D03*
Y404866D03*
Y400066D03*
X722100Y368300D03*
X717300D03*
X712500D03*
X742200Y380400D03*
Y370800D03*
Y375600D03*
X728700Y381000D03*
Y376200D03*
Y371400D03*
X722100Y363500D03*
X717300D03*
X712500D03*
X705900Y386900D03*
X711000Y395100D03*
X710900Y386800D03*
X706000Y395100D03*
X725247Y458974D03*
X724422Y464139D03*
X724400Y485200D03*
Y480400D03*
Y475600D03*
X740900Y476400D03*
Y469400D03*
Y461900D03*
X704340Y468062D03*
X705400Y477400D03*
X724400Y490200D03*
X702550Y565366D03*
X707550D03*
X712550D03*
X717550D03*
X722550D03*
X727550D03*
X732550D03*
X737550D03*
X742550D03*
X747550D03*
X752550D03*
X757550D03*
X821272Y49340D03*
Y44340D03*
Y39340D03*
Y34340D03*
Y29340D03*
Y24340D03*
Y19340D03*
Y14340D03*
Y9340D03*
X815364Y5500D03*
X810364D03*
X805364D03*
X800364D03*
X795364D03*
X790364D03*
X785364D03*
X780364D03*
X775364D03*
X770364D03*
X765364D03*
X821272Y114340D03*
Y109340D03*
Y104340D03*
Y99340D03*
Y94340D03*
Y89340D03*
Y84340D03*
Y79340D03*
Y74340D03*
Y69340D03*
Y64340D03*
Y59340D03*
Y54340D03*
Y174340D03*
Y169340D03*
Y164340D03*
Y159340D03*
Y154340D03*
Y149340D03*
Y144340D03*
Y139340D03*
Y134340D03*
Y129340D03*
Y124340D03*
Y119340D03*
Y234340D03*
Y229340D03*
Y224340D03*
Y219340D03*
Y214340D03*
Y209340D03*
Y204340D03*
Y199340D03*
Y194340D03*
Y189340D03*
Y184340D03*
Y179340D03*
X771083Y211784D03*
X821272Y299340D03*
Y294340D03*
Y289340D03*
Y284340D03*
Y279340D03*
Y274340D03*
Y269340D03*
Y264340D03*
Y259340D03*
Y254340D03*
Y249340D03*
Y244340D03*
Y239340D03*
Y359340D03*
Y354340D03*
Y349340D03*
Y344340D03*
Y339340D03*
Y334340D03*
Y329340D03*
Y324340D03*
Y319340D03*
Y314340D03*
Y309340D03*
Y304340D03*
Y424340D03*
Y419340D03*
Y414340D03*
Y409340D03*
Y404340D03*
Y399340D03*
Y394340D03*
Y389340D03*
Y384340D03*
Y379340D03*
Y374340D03*
Y369340D03*
Y364340D03*
Y484340D03*
Y479340D03*
Y474340D03*
Y469340D03*
Y464340D03*
Y459340D03*
Y454340D03*
Y449340D03*
Y444340D03*
Y439340D03*
Y434340D03*
Y429340D03*
Y504340D03*
Y509340D03*
Y514340D03*
Y519340D03*
Y524340D03*
Y529340D03*
Y549340D03*
Y544340D03*
Y539340D03*
Y534340D03*
Y499340D03*
Y494340D03*
Y489340D03*
X762550Y565366D03*
X767550D03*
X772550D03*
X777550D03*
X782550D03*
X787550D03*
X792550D03*
X797550D03*
X802550D03*
X807550D03*
X812550D03*
X817550D03*
X821272Y559340D03*
Y554340D03*
G54D30*
X254300Y369300D03*
X300500Y144300D03*
X301000Y228800D03*
X300500Y186300D03*
X362810Y254940D03*
X362868Y283087D03*
X362677Y310862D03*
X581500Y464800D03*
X676531Y385433D03*
X788107Y128193D03*
G54D21*
X149858Y418270D03*
X261712Y59618D03*
X619226Y234952D03*
X581700Y449500D03*
X660145Y23414D03*
X667177Y135318D03*
X667118Y141825D03*
X698089Y169842D03*
X684200Y128700D03*
X676582Y128735D03*
X641123Y144911D03*
X641150Y134900D03*
X641100Y148800D03*
X671092Y195715D03*
X663412Y195705D03*
X654400Y238400D03*
X684512Y480221D03*
X704988Y145327D03*
X705610Y169842D03*
X726055Y195527D03*
X721304Y329638D03*
G54D12*
X37700Y64400D03*
X86150Y441700D03*
X737400Y485700D03*
G54D31*
X262600Y416700D03*
X301000Y164800D03*
X300500Y204800D03*
Y247300D03*
X362868Y269041D03*
X362689Y297141D03*
X631781Y134308D03*
X639120Y457930D03*
X776500Y114300D03*
X790000Y98300D03*
X776500D03*
G54D40*
X283000Y286300D03*
X316786Y386542D03*
X358169Y265368D03*
X358222Y292641D03*
X413400Y340600D03*
X417400D03*
X449400Y330800D03*
X427500Y340600D03*
X432900Y340900D03*
X445400Y330800D03*
X447300Y340900D03*
X391900Y340700D03*
X450200Y322200D03*
X510000Y351600D03*
X506000D03*
X505379Y341811D03*
X501281D03*
X509517Y341846D03*
X502200Y360609D03*
X455900Y340800D03*
X478618Y339442D03*
X547908Y331732D03*
X541747Y331765D03*
X529947Y331800D03*
X525522Y341846D03*
X529622D03*
X558000Y348300D03*
X554000D03*
X533947Y331800D03*
X540200Y351400D03*
X536200D03*
X545200D03*
X549200D03*
X633000Y62300D03*
X636000Y203300D03*
X632000D03*
X624000D03*
X628000D03*
X618026Y261552D03*
X611526D03*
X659850Y46800D03*
X641003Y62309D03*
X640000Y203300D03*
X648000D03*
X652000D03*
X644000D03*
X656000D03*
X660000D03*
X645500Y261200D03*
X652000D03*
X672131Y383183D03*
X717500Y135250D03*
X713500D03*
X710800Y214600D03*
X719700D03*
X785350Y84300D03*
X794500Y137400D03*
X782500D03*
X798500D03*
X796500Y229300D03*
G54D22*
X153458Y418270D03*
X265312Y59618D03*
X622826Y234952D03*
X585300Y449500D03*
X663745Y23414D03*
X670777Y135318D03*
X670718Y141825D03*
X687800Y128700D03*
X680182Y128735D03*
X644723Y144911D03*
X644750Y134900D03*
X644700Y148800D03*
X674692Y195715D03*
X667012Y195705D03*
X658000Y238400D03*
X688112Y480221D03*
X708588Y145327D03*
X701689Y169842D03*
X709210D03*
X729655Y195527D03*
X724904Y329638D03*
G54D13*
X38502Y161319D03*
X49302D03*
X43902D03*
X49302Y150519D03*
Y155919D03*
X43902Y150519D03*
Y155919D03*
X38502D03*
Y150519D03*
X34567Y205090D03*
X108672Y138471D03*
Y132871D03*
X90672Y138471D03*
X102672D03*
X96672D03*
X84672D03*
Y132871D03*
X96672D03*
X102672D03*
X90672D03*
X128611Y331774D03*
X121506Y349295D03*
X129133Y339988D03*
X114258Y351996D03*
X186054Y105503D03*
X170652Y119800D03*
X177400Y149700D03*
X140561Y420016D03*
X140820Y436738D03*
X140712Y444036D03*
X204818Y107083D03*
X238000Y149500D03*
X248746Y140710D03*
X246764Y199671D03*
X237682Y343985D03*
X259132Y405962D03*
X226076Y407980D03*
X226376Y419280D03*
X250400Y407800D03*
X237276Y408080D03*
X237576Y419380D03*
X248698Y372535D03*
X276700Y66700D03*
X307243Y156439D03*
X270486Y130871D03*
X320000Y180000D03*
X316500Y228500D03*
X316263Y211751D03*
X275519Y213859D03*
X323700Y284500D03*
X309300Y283300D03*
X306292Y252825D03*
X302262Y262642D03*
X296000Y287000D03*
X276070Y401100D03*
X321467Y383273D03*
X298152Y389992D03*
X269742Y380801D03*
X266050Y385047D03*
X344484Y265072D03*
X343314Y272604D03*
X383677Y252037D03*
X379700Y279906D03*
X385803Y260151D03*
X332000Y266336D03*
X337500Y266050D03*
X371160Y314500D03*
X386159Y327300D03*
X335133Y412340D03*
X407484Y262952D03*
X437233Y263915D03*
X391839Y263634D03*
X389709Y245772D03*
X413115Y323215D03*
X425737Y325715D03*
X427165Y316929D03*
X435039D03*
X442913Y320866D03*
X431203Y326380D03*
X401700Y340950D03*
X392453Y331635D03*
X496828Y199110D03*
X505776Y198689D03*
X484392Y298681D03*
X477955Y301006D03*
X490158Y309055D03*
X500300Y328154D03*
X479600Y310300D03*
X501227Y354336D03*
X460484Y350953D03*
X491445Y342700D03*
X474210Y316992D03*
X462663Y323248D03*
X475834Y331163D03*
X481856Y352656D03*
X468257Y323578D03*
X498032Y312992D03*
X473265Y322929D03*
X454724Y301181D03*
X495050Y373662D03*
X506684Y455873D03*
X529512Y352016D03*
X572204Y407700D03*
X570669Y465918D03*
X532050Y476200D03*
X550100Y479850D03*
X569400Y483400D03*
X569402Y472058D03*
X561657Y461261D03*
X540140Y489830D03*
X633803Y27749D03*
X629500Y118500D03*
X599000Y236500D03*
X630500Y212900D03*
X631600Y271000D03*
X603000Y279000D03*
X611606Y322456D03*
X623969Y319984D03*
X594200Y395200D03*
X604832Y395220D03*
X605148Y440842D03*
X587250Y463750D03*
X577390Y453170D03*
X621308Y468700D03*
X633850Y452930D03*
X609768Y487900D03*
X652587Y21500D03*
X639426Y49015D03*
X640144Y40969D03*
X659850Y42534D03*
X639900Y27100D03*
X646000Y62259D03*
X661644Y164498D03*
X636630Y154650D03*
X645729Y161603D03*
X657700Y139700D03*
X657570Y146235D03*
X663800Y148100D03*
X680425Y205984D03*
X656427Y226217D03*
X638361Y212930D03*
X673100Y238300D03*
X652000Y220500D03*
X668153Y210095D03*
X650904Y226864D03*
X684696Y236469D03*
X695253Y214735D03*
X689783Y215075D03*
X686982Y262854D03*
X678720Y288330D03*
X686912Y268500D03*
X653707Y342389D03*
X667400Y384700D03*
X662029Y384727D03*
X657031Y384900D03*
X680700Y373763D03*
X684017Y389383D03*
X650530Y379699D03*
X668800Y478000D03*
X668300Y464300D03*
X701900Y106000D03*
X712399Y160987D03*
X732579Y152616D03*
X715490Y131490D03*
X749533Y160800D03*
X749500Y145050D03*
X750000Y141000D03*
X748000Y167000D03*
X703290Y205505D03*
X716096Y272396D03*
X700600Y256539D03*
X711401Y477794D03*
X804300Y111300D03*
X785050Y79670D03*
X771371Y98500D03*
X766694Y86024D03*
X767200Y113600D03*
X800000Y145240D03*
X793378Y145309D03*
X785756Y145353D03*
X805200Y170300D03*
X804600Y130300D03*
X773100Y132000D03*
X765900Y119700D03*
X790050Y178350D03*
X782850D03*
X795450Y178550D03*
X800500Y232750D03*
X775486Y287316D03*
G54D14*
X46277Y517441D03*
G54D23*
X148138Y423870D03*
X155738D03*
X172738Y425870D03*
X165138D03*
X172738Y417870D03*
X165138D03*
X148138Y431470D03*
X155738D03*
X248600Y238500D03*
X241000D03*
X248600Y230900D03*
X241000D03*
X248600Y223300D03*
X241000D03*
X248600Y215700D03*
X241000D03*
X248600Y208100D03*
X241000D03*
X255200Y375750D03*
X262800D03*
X281300Y156500D03*
X273700D03*
X281300Y147500D03*
X273700D03*
X281300Y231000D03*
X273700D03*
X281300Y189500D03*
X273700D03*
X281300Y239500D03*
X273700D03*
X281300Y198000D03*
X273700D03*
X522812Y470071D03*
X515212D03*
X523000Y462400D03*
X515400D03*
X617726Y244452D03*
X625326D03*
X610826D03*
X603226D03*
X675462Y162183D03*
X667862D03*
X675597Y177941D03*
X667997D03*
X675735Y187351D03*
X668135D03*
X645800Y244000D03*
X638200D03*
X652700D03*
X660300D03*
X643100Y364900D03*
X650700D03*
X682000Y466700D03*
X689600D03*
X682000Y474366D03*
X689600D03*
X719304Y345038D03*
X726904D03*
X719304Y353038D03*
X726904D03*
X797800Y112500D03*
X790200D03*
X802307Y124593D03*
X794707D03*
G54D50*
X367340Y250340D03*
Y253940D03*
X367368Y278487D03*
Y282087D03*
X367177Y306562D03*
Y310162D03*
X422323Y284048D03*
Y287648D03*
X418323Y284048D03*
Y287648D03*
X467534Y252200D03*
Y255800D03*
X467547Y259450D03*
Y263050D03*
X467537Y268396D03*
Y271996D03*
X775407Y123893D03*
Y127493D03*
G54D32*
X262600Y411100D03*
X301000Y159200D03*
X300500Y199200D03*
Y241700D03*
X362868Y263441D03*
X362689Y291541D03*
X631781Y128708D03*
X639120Y452330D03*
X776500Y108700D03*
X790000Y92700D03*
X776500D03*
G54D41*
X283000Y289700D03*
X316786Y389942D03*
X358169Y268768D03*
X358222Y296041D03*
X413400Y344000D03*
X417400D03*
X449400Y334200D03*
X427500Y344000D03*
X432900Y344300D03*
X445400Y334200D03*
X447300Y344300D03*
X391900Y344100D03*
X450200Y325600D03*
X510000Y355000D03*
X506000D03*
X505379Y345211D03*
X501281D03*
X509517Y345246D03*
X455900Y344200D03*
X478618Y342842D03*
X502200Y364009D03*
X547908Y335132D03*
X541747Y335165D03*
X529947Y335200D03*
X525522Y345246D03*
X529622D03*
X558000Y351700D03*
X554000D03*
X533947Y335200D03*
X540200Y354800D03*
X536200D03*
X545200D03*
X549200D03*
X633000Y65700D03*
X636000Y206700D03*
X632000D03*
X624000D03*
X628000D03*
X618026Y264952D03*
X611526D03*
X659850Y50200D03*
X641003Y65709D03*
X640000Y206700D03*
X648000D03*
X652000D03*
X644000D03*
X656000D03*
X660000D03*
X645500Y264600D03*
X652000D03*
X672131Y386583D03*
X717500Y138650D03*
X713500D03*
X710800Y218000D03*
X719700D03*
X785350Y87700D03*
X794500Y140800D03*
X782500D03*
X798500D03*
X796500Y232700D03*
G54D33*
X285500Y55518D03*
X281700D03*
X426300Y245700D03*
X644950Y36700D03*
X660300Y150000D03*
X667300Y151100D03*
X689132Y196295D03*
X669000Y246200D03*
X804500Y178530D03*
G54D24*
X166138Y432870D03*
X542495Y471383D03*
X604226Y252452D03*
X639200Y252000D03*
G54D51*
X367368Y268041D03*
Y264441D03*
X369889Y296241D03*
Y292641D03*
X492132Y300373D03*
Y296773D03*
X469490Y295572D03*
Y291972D03*
X465640Y295572D03*
Y291972D03*
X651430Y174234D03*
Y170634D03*
X772000Y113300D03*
Y109700D03*
G54D42*
X321787Y278970D03*
X325287D03*
X444850Y243879D03*
X438000D03*
X430470D03*
X475500D03*
X459500D03*
X451500D03*
X467600D03*
X645248Y47895D03*
X648748D03*
X652248D03*
X656051Y46793D03*
X660450Y135900D03*
X716517Y189323D03*
X771607Y127493D03*
X800600Y182130D03*
G54D15*
X37402Y499724D03*
X789370D03*
G54D60*
X389764Y460630D03*
X437008D03*
G54D34*
X285500Y59118D03*
X281700D03*
X426300Y249300D03*
X644950Y40300D03*
X660300Y153600D03*
X667300Y154700D03*
X689132Y199895D03*
X669000Y249800D03*
X804500Y182130D03*
G54D70*
X687500Y274750D03*
X683625Y282250D03*
X691375D03*
G54D52*
X352230Y247771D03*
Y255371D03*
X352228Y275887D03*
Y283487D03*
X352254Y269441D03*
Y261841D03*
X352222Y297541D03*
Y289941D03*
X352214Y303962D03*
Y311562D03*
X625300Y103200D03*
Y110800D03*
X625281Y127708D03*
Y135308D03*
X624026Y267252D03*
Y259652D03*
X605526Y267252D03*
Y259652D03*
X627570Y452930D03*
Y460530D03*
X619200Y441200D03*
Y433600D03*
X626900Y441200D03*
Y433600D03*
X687375Y177704D03*
Y185304D03*
X696761Y177683D03*
Y185283D03*
X639500Y266800D03*
Y259200D03*
X658000Y266800D03*
Y259200D03*
X706195Y177658D03*
Y185258D03*
X783000Y107700D03*
Y115300D03*
X781507Y129393D03*
Y121793D03*
G54D61*
X425845Y231050D03*
X423645D03*
X425845Y233550D03*
X423645D03*
X396100Y226300D03*
X393900D03*
X396900Y230300D03*
X394700D03*
X435267Y273353D03*
X433067D03*
X428400Y257900D03*
X426200D03*
X419600Y254000D03*
X417400D03*
X428400D03*
X426200D03*
X409000Y250900D03*
X406800D03*
X436018Y257827D03*
X433818D03*
X504922Y230291D03*
X502722D03*
X504922Y218500D03*
X502722D03*
X504922Y226350D03*
X502722D03*
X504922Y222450D03*
X502722D03*
X504922Y214576D03*
X502722D03*
X504922Y234219D03*
X502722D03*
X483700Y285200D03*
X481500D03*
X490350Y242150D03*
X488150D03*
X483300Y238100D03*
X481100D03*
X483300Y273600D03*
X481100D03*
X483282Y265195D03*
X481082D03*
X483300Y269650D03*
X481100D03*
X490250Y281500D03*
X488050D03*
X490400Y257900D03*
X488200D03*
X483300Y249950D03*
X481100D03*
X483300Y281550D03*
X481100D03*
X490400Y246000D03*
X488200D03*
X508186Y289438D03*
X505986D03*
X490400Y261950D03*
X488200D03*
X490400Y253900D03*
X488200D03*
X483300Y246000D03*
X481100D03*
X507100Y262500D03*
X504900D03*
X483300Y257800D03*
X481100D03*
X483300Y277600D03*
X481100D03*
X483300Y242100D03*
X481100D03*
X490400Y250000D03*
X488200D03*
X483300Y253900D03*
X481100D03*
X490400Y269700D03*
X488200D03*
X491400Y289300D03*
X489200D03*
X483282Y262695D03*
X481082D03*
X499200Y309020D03*
X497000D03*
X542100Y291500D03*
X539900D03*
X542300Y287400D03*
X540100D03*
X542300Y285200D03*
X540100D03*
X542300Y281300D03*
X540100D03*
X542300Y279100D03*
X540100D03*
X542300Y275200D03*
X540100D03*
X542300Y273000D03*
X540100D03*
X542300Y269100D03*
X540100D03*
X542300Y266900D03*
X540100D03*
X542300Y263100D03*
X540100D03*
X542300Y260900D03*
X540100D03*
X530601Y256167D03*
X528401D03*
X530601Y253967D03*
X528401D03*
X537200Y297600D03*
X535000D03*
X537200Y299800D03*
X535000D03*
X542100Y293700D03*
X539900D03*
X514600Y310000D03*
X512400D03*
X537500Y317200D03*
X535300D03*
X537500Y319400D03*
X535300D03*
X537400Y311200D03*
X535200D03*
X537400Y313400D03*
X535200D03*
X537300Y305100D03*
X535100D03*
X537300Y307300D03*
X535100D03*
X651483Y111296D03*
X649283D03*
X651483Y108996D03*
X649283D03*
X685300Y162630D03*
X683100D03*
X678747Y171175D03*
X676547D03*
X678747Y168975D03*
X676547D03*
X685250Y168930D03*
X683050D03*
X685300Y164830D03*
X683100D03*
X685250Y171130D03*
X683050D03*
X692141Y189723D03*
X689941D03*
X684682Y195495D03*
X682482D03*
X686992Y189743D03*
X684792D03*
X722142Y170065D03*
X719942D03*
X723000Y164200D03*
X720800D03*
X722242Y157715D03*
X720042D03*
X722142Y151175D03*
X719942D03*
X722142Y145165D03*
X719942D03*
X723200Y139500D03*
X721000D03*
X723452Y132025D03*
X721252D03*
X702400Y125000D03*
X700200D03*
X707600D03*
X705400D03*
X713100D03*
X710900D03*
X718600D03*
X716400D03*
X707435Y189777D03*
X705235D03*
X722142Y189185D03*
X719942D03*
X722142Y182795D03*
X719942D03*
X722142Y176315D03*
X719942D03*
X701588Y189806D03*
X699388D03*
G54D43*
X321787Y275370D03*
X325287D03*
X444850Y240279D03*
X438000D03*
X430470D03*
X475500D03*
X459500D03*
X451500D03*
X467600D03*
X645248Y44295D03*
X648748D03*
X652248D03*
X656051Y43193D03*
X660450Y132300D03*
X716517Y185723D03*
X771607Y123893D03*
X800600Y178530D03*
G54D16*
X37402Y535158D03*
X789370D03*
G54D25*
X171738Y432870D03*
X548095Y471383D03*
X609826Y252452D03*
X644800Y252000D03*
G54D26*
X153038Y443136D03*
X171038D03*
G54D44*
X290425Y297650D03*
X292395D03*
X294360D03*
X296330D03*
X298300D03*
X300270D03*
X302235D03*
X304205D03*
X306175D03*
X308140D03*
X310110D03*
X312080D03*
X314045D03*
X316015D03*
X317985D03*
X319955D03*
X321920D03*
X323890D03*
Y373350D03*
X321920D03*
X319955D03*
X317985D03*
X316015D03*
X314045D03*
X312080D03*
X310110D03*
X308140D03*
X306175D03*
X304205D03*
X302235D03*
X300270D03*
X298300D03*
X296330D03*
X294360D03*
X292395D03*
X290425D03*
X325860Y297650D03*
X327825D03*
X329795D03*
X331765D03*
X333730D03*
X335700D03*
X337670D03*
X339640D03*
X341605D03*
X343575D03*
Y373350D03*
X341605D03*
X339640D03*
X337670D03*
X335700D03*
X333730D03*
X331765D03*
X329795D03*
X327825D03*
X325860D03*
G54D35*
X280800Y141000D03*
X280300Y163000D03*
X280800Y204500D03*
Y224500D03*
X280300Y183000D03*
Y246000D03*
X624326Y252452D03*
X659300Y252000D03*
X725904Y338538D03*
G54D53*
X371698Y341070D03*
X376784Y310847D03*
X419979Y263835D03*
X398230Y331430D03*
X483144Y359195D03*
X450841Y351640D03*
X454341Y356355D03*
X478300Y371800D03*
X524250Y476000D03*
X516750D03*
X574100Y483400D03*
Y487900D03*
X641800Y166000D03*
X679384Y201545D03*
X690050Y236469D03*
X692300Y210200D03*
X678789Y262854D03*
X735100Y97900D03*
X734252Y160315D03*
X757115Y136383D03*
X753800Y169500D03*
X757115Y140433D03*
X754021Y145050D03*
X754300Y160800D03*
X757115Y132181D03*
X706047Y138406D03*
X736879Y151899D03*
X721404Y333538D03*
X791800Y106500D03*
X796807Y130593D03*
X779841Y182831D03*
X787750Y182850D03*
G54D71*
X673000Y282250D03*
X676875Y274750D03*
X669125D03*
X776000Y85750D03*
X779875Y78250D03*
X772125D03*
X799500Y100750D03*
X803375Y93250D03*
X795625D03*
G54D17*
X116063Y14567D03*
G54D62*
X407500Y237100D03*
X411398Y231600D03*
Y229400D03*
X395500Y235300D03*
Y233100D03*
X420700Y227400D03*
Y225200D03*
X435600Y227400D03*
Y225200D03*
X430200Y227400D03*
Y225200D03*
X438100Y227400D03*
Y225200D03*
X438500Y235150D03*
Y232950D03*
X445900Y227400D03*
Y225200D03*
X431050Y235150D03*
Y232950D03*
X446400Y235150D03*
Y232950D03*
X427700Y227400D03*
Y225200D03*
X423200Y227400D03*
Y225200D03*
X443900Y235150D03*
Y232950D03*
X436000Y235150D03*
Y232950D03*
X428550Y235150D03*
Y232950D03*
X443400Y227400D03*
Y225200D03*
X412000Y265100D03*
Y262900D03*
X411436Y246100D03*
Y243900D03*
X414500Y265100D03*
Y262900D03*
X407500Y239300D03*
X443700Y284200D03*
Y282000D03*
X430300Y284600D03*
Y282400D03*
X446500Y284200D03*
Y282000D03*
X395500Y243200D03*
Y241000D03*
X435400Y284200D03*
Y282000D03*
X437900Y284200D03*
Y282000D03*
X427635Y241981D03*
Y239781D03*
X428000Y284600D03*
Y282400D03*
X445900Y262350D03*
Y260150D03*
X443500Y271400D03*
Y269200D03*
Y254950D03*
Y252750D03*
X443400Y262350D03*
Y260150D03*
X446000Y271400D03*
Y269200D03*
Y254950D03*
Y252750D03*
X415400Y314500D03*
Y312300D03*
X482750Y227400D03*
Y225200D03*
X462200Y235150D03*
Y232950D03*
X461650Y227400D03*
Y225200D03*
X454340Y235150D03*
Y232950D03*
X467600Y235150D03*
Y232950D03*
X459700Y235150D03*
Y232950D03*
X470100Y235150D03*
Y232950D03*
X496059Y205807D03*
Y203607D03*
X482402Y235178D03*
Y232978D03*
X475400Y235150D03*
Y232950D03*
X469550Y227400D03*
Y225200D03*
X474900Y227400D03*
Y225200D03*
X454150Y227400D03*
Y225200D03*
X459150Y227400D03*
Y225200D03*
X485250Y227400D03*
Y225200D03*
X477400Y227400D03*
Y225200D03*
X451650Y227400D03*
Y225200D03*
X477900Y235150D03*
Y232950D03*
X467050Y227400D03*
Y225200D03*
X451840Y235150D03*
Y232950D03*
X451200Y284100D03*
Y281900D03*
X478400Y285600D03*
Y283400D03*
X474520Y285600D03*
Y283400D03*
X470490Y284400D03*
Y282200D03*
X458100Y284100D03*
Y281900D03*
X465800Y284200D03*
Y282000D03*
X463300Y284200D03*
Y282000D03*
X455800Y284102D03*
Y281902D03*
X453500Y284100D03*
Y281900D03*
X459500Y271400D03*
Y269200D03*
X462000Y271400D03*
Y269200D03*
X451450Y254950D03*
Y252750D03*
X459450Y254950D03*
Y252750D03*
X454550Y262350D03*
Y260150D03*
X454000Y271400D03*
Y269200D03*
X459500Y262350D03*
Y260150D03*
X451500Y271400D03*
Y269200D03*
X453950Y254950D03*
Y252750D03*
X452050Y262350D03*
Y260150D03*
X461950Y254950D03*
Y252750D03*
X462000Y262350D03*
Y260150D03*
X649307Y82136D03*
Y79936D03*
X651807Y82136D03*
Y79936D03*
X656080Y82096D03*
Y79896D03*
X658580Y82096D03*
Y79896D03*
X665285Y83804D03*
Y81604D03*
X667550Y83794D03*
Y81594D03*
X672926Y83330D03*
Y81130D03*
X675326Y83330D03*
Y81130D03*
X681283Y83329D03*
Y81129D03*
X683563Y83330D03*
Y81130D03*
X689149Y83598D03*
Y81398D03*
X691382Y83599D03*
Y81399D03*
X696418Y141404D03*
Y139204D03*
X656875Y173552D03*
Y171352D03*
X683698Y141105D03*
Y138905D03*
X694192Y141403D03*
Y139203D03*
X687898Y141112D03*
Y138912D03*
X690100Y141100D03*
Y138900D03*
X663507Y189280D03*
Y187080D03*
X649027Y191577D03*
Y189377D03*
X656944Y179504D03*
Y177304D03*
X657045Y185173D03*
Y182973D03*
X721320Y128695D03*
Y126495D03*
G54D27*
X254800Y415000D03*
X316100Y290100D03*
X342200Y285800D03*
Y277770D03*
X380771Y332810D03*
X476300Y270600D03*
X476200Y262500D03*
X476500Y249200D03*
X476400Y254800D03*
X557800Y461260D03*
X520200Y456800D03*
X608526Y234952D03*
X651254Y138591D03*
X650317Y116114D03*
Y119614D03*
X676752Y150915D03*
Y154415D03*
X686202Y145315D03*
X686200Y151100D03*
X686100Y157350D03*
X664200Y128650D03*
X644200Y238400D03*
X721933Y195408D03*
X707262Y195365D03*
X699652Y194895D03*
G54D63*
X433218Y253101D03*
X436818D03*
X472600Y278500D03*
X476200D03*
X605026Y238652D03*
X608626D03*
X647700Y125850D03*
X651300D03*
X697700Y119500D03*
X640700Y234700D03*
X644300D03*
X711700Y119500D03*
X715300D03*
X704700D03*
X708300D03*
X701300D03*
X711001Y195267D03*
X714601D03*
G54D45*
X295275Y531496D03*
X531495D03*
G54D72*
X669700Y366779D03*
X680700D03*
G54D36*
X275200Y141000D03*
X274700Y163000D03*
X275200Y204500D03*
Y224500D03*
X274700Y183000D03*
Y246000D03*
X618726Y252452D03*
X653700Y252000D03*
X720304Y338538D03*
G54D54*
X375098Y341070D03*
X380184Y310847D03*
X423379Y263835D03*
X401630Y331430D03*
X486544Y359195D03*
X454241Y351640D03*
X457741Y356355D03*
X481700Y371800D03*
X527650Y476000D03*
X520150D03*
X577500Y483400D03*
Y487900D03*
X645200Y166000D03*
X682784Y201545D03*
X693450Y236469D03*
X695700Y210200D03*
X682189Y262854D03*
X738500Y97900D03*
X737652Y160315D03*
X757200Y169500D03*
X757421Y145050D03*
X757700Y160800D03*
X709447Y138406D03*
X740279Y151899D03*
X724804Y333538D03*
X795200Y106500D03*
X760515Y136383D03*
Y140433D03*
Y132181D03*
X800207Y130593D03*
X783241Y182831D03*
X791150Y182850D03*
G54D18*
X116063Y39075D03*
G54D28*
X251200Y415000D03*
X312500Y290100D03*
X338600Y285800D03*
Y277770D03*
X377171Y332810D03*
X472700Y270600D03*
X472600Y262500D03*
X472900Y249200D03*
X472800Y254800D03*
X554200Y461260D03*
X516600Y456800D03*
X604926Y234952D03*
X647654Y138591D03*
X646717Y116114D03*
Y119614D03*
X673152Y150915D03*
Y154415D03*
X682602Y145315D03*
X682600Y151100D03*
X682500Y157350D03*
X660600Y128650D03*
X696052Y194895D03*
X640600Y238400D03*
X718333Y195408D03*
X703662Y195365D03*
G54D55*
X381083Y314895D03*
X402658Y262952D03*
X432789Y267240D03*
X412950Y330250D03*
X440186Y351341D03*
X411420Y335630D03*
X501900Y194800D03*
X490044Y354873D03*
X481800Y367500D03*
Y363400D03*
X498500Y368350D03*
X545695Y480090D03*
X569939Y461261D03*
X574033Y476488D03*
X657713Y166929D03*
X688200Y210200D03*
X672900Y288000D03*
X682189Y268500D03*
X740279Y155899D03*
X716046Y276558D03*
X762570Y81900D03*
X762540Y77810D03*
X762570Y86100D03*
G54D37*
X290000Y136500D03*
Y147500D03*
Y167500D03*
Y156500D03*
Y239500D03*
Y209000D03*
Y198000D03*
Y220000D03*
Y231000D03*
Y178500D03*
Y189500D03*
Y250500D03*
G54D73*
X658500Y368750D03*
G54D64*
X401575Y410039D03*
X410433D03*
X419292D03*
X404528Y412795D03*
X413386D03*
X422244D03*
X401575Y425000D03*
X410433D03*
X419292D03*
X407480Y422244D03*
X416339D03*
X425197D03*
X407480Y407284D03*
X416339D03*
X425197D03*
X404528Y427756D03*
X413386D03*
X422244D03*
X401575Y439961D03*
X410433D03*
X419292D03*
X404528Y442717D03*
X413386D03*
X422244D03*
X401575Y454921D03*
X410433D03*
X419292D03*
X404528Y457677D03*
X413386D03*
X422244D03*
X407480Y437205D03*
X416339D03*
X425197D03*
X407480Y452165D03*
X416339D03*
X425197D03*
G54D19*
X98425Y472441D03*
X137795D03*
G54D46*
X388189Y48426D03*
X374016D03*
X359843D03*
X345670D03*
X388189Y34252D03*
X374016D03*
X359843D03*
X345670D03*
X388189Y20079D03*
X374016D03*
X359843D03*
X345670D03*
X388189Y44095D03*
X374016D03*
X359843D03*
X345670D03*
X388189Y38583D03*
X374016D03*
X359843D03*
X345670D03*
X388189Y29922D03*
X374016D03*
X359843D03*
X345670D03*
X388189Y24410D03*
X374016D03*
X359843D03*
X345670D03*
X388189Y15748D03*
X374016D03*
X359843D03*
X345670D03*
X388189Y10237D03*
X374016D03*
X359843D03*
X345670D03*
X388189Y5906D03*
X374016D03*
X359843D03*
X345670D03*
X381103Y38977D03*
X366929D03*
X352756D03*
X338583D03*
X381103Y24804D03*
X366929D03*
X352756D03*
X338583D03*
X381103Y53150D03*
X366929D03*
X352756D03*
X338583D03*
X381103Y48819D03*
X366929D03*
X352756D03*
X338583D03*
X381103Y43307D03*
X366929D03*
X352756D03*
X338583D03*
X381103Y34646D03*
X366929D03*
X352756D03*
X338583D03*
X381103Y29134D03*
X366929D03*
X352756D03*
X338583D03*
X381103Y20473D03*
X366929D03*
X352756D03*
X338583D03*
X381103Y14961D03*
X366929D03*
X352756D03*
X338583D03*
X444882Y48426D03*
X430709D03*
X416536D03*
X402363D03*
X444882Y34252D03*
X430709D03*
X416536D03*
X402363D03*
X444882Y20079D03*
X430709D03*
X416536D03*
X402363D03*
X444882Y44095D03*
X430709D03*
X416536D03*
X402363D03*
X444882Y38583D03*
X430709D03*
X416536D03*
X402363D03*
X444882Y29922D03*
X430709D03*
X416536D03*
X402363D03*
X444882Y24410D03*
X430709D03*
X416536D03*
X402363D03*
X444882Y15748D03*
X430709D03*
X416536D03*
X402363D03*
X444882Y10237D03*
X430709D03*
X416536D03*
X402363D03*
X444882Y5906D03*
X430709D03*
X416536D03*
X402363D03*
X437796Y38977D03*
X423622D03*
X409449D03*
X395276D03*
X437796Y24804D03*
X423622D03*
X409449D03*
X395276D03*
X437796Y53150D03*
X423622D03*
X409449D03*
X395276D03*
X437796Y48819D03*
X423622D03*
X409449D03*
X395276D03*
X437796Y43307D03*
X423622D03*
X409449D03*
X395276D03*
X437796Y34646D03*
X423622D03*
X409449D03*
X395276D03*
X437796Y29134D03*
X423622D03*
X409449D03*
X395276D03*
X437796Y20473D03*
X423622D03*
X409449D03*
X395276D03*
X437796Y14961D03*
X423622D03*
X409449D03*
X395276D03*
X501575Y48426D03*
X487402D03*
X473229D03*
X459055D03*
X501575Y34252D03*
X487402D03*
X473229D03*
X459055D03*
X501575Y20079D03*
X487402D03*
X473229D03*
X459055D03*
X501575Y44095D03*
X487402D03*
X473229D03*
X459055D03*
X501575Y38583D03*
X487402D03*
X473229D03*
X459055D03*
X501575Y29922D03*
X487402D03*
X473229D03*
X459055D03*
X501575Y24410D03*
X487402D03*
X473229D03*
X459055D03*
X501575Y15748D03*
X487402D03*
X473229D03*
X459055D03*
X501575Y10237D03*
X487402D03*
X473229D03*
X459055D03*
X501575Y5906D03*
X487402D03*
X473229D03*
X459055D03*
X508662Y38977D03*
X494489D03*
X480315D03*
X466142D03*
X451969D03*
X508662Y24804D03*
X494489D03*
X480315D03*
X466142D03*
X451969D03*
X508662Y53150D03*
X494489D03*
X480315D03*
X466142D03*
X451969D03*
X508662Y48819D03*
X494489D03*
X480315D03*
X466142D03*
X451969D03*
X508662Y43307D03*
X494489D03*
X480315D03*
X466142D03*
X451969D03*
X508662Y34646D03*
X494489D03*
X480315D03*
X466142D03*
X451969D03*
X508662Y29134D03*
X494489D03*
X480315D03*
X466142D03*
X451969D03*
X508662Y20473D03*
X494489D03*
X480315D03*
X466142D03*
X451969D03*
X508662Y14961D03*
X494489D03*
X480315D03*
X466142D03*
X451969D03*
X572441Y48426D03*
X558268D03*
X544095D03*
X529922D03*
X515748D03*
X572441Y34252D03*
X558268D03*
X544095D03*
X529922D03*
X515748D03*
X572441Y20079D03*
X558268D03*
X544095D03*
X529922D03*
X515748D03*
X572441Y44095D03*
X558268D03*
X544095D03*
X529922D03*
X515748D03*
X572441Y38583D03*
X558268D03*
X544095D03*
X529922D03*
X515748D03*
X572441Y29922D03*
X558268D03*
X544095D03*
X529922D03*
X515748D03*
X572441Y24410D03*
X558268D03*
X544095D03*
X529922D03*
X515748D03*
X572441Y15748D03*
X558268D03*
X544095D03*
X529922D03*
X515748D03*
X572441Y10237D03*
X558268D03*
X544095D03*
X529922D03*
X515748D03*
X572441Y5906D03*
X558268D03*
X544095D03*
X529922D03*
X515748D03*
X565355Y38977D03*
X551181D03*
X537008D03*
X522835D03*
X565355Y24804D03*
X551181D03*
X537008D03*
X522835D03*
X565355Y53150D03*
X551181D03*
X537008D03*
X522835D03*
X565355Y48819D03*
X551181D03*
X537008D03*
X522835D03*
X565355Y43307D03*
X551181D03*
X537008D03*
X522835D03*
X565355Y34646D03*
X551181D03*
X537008D03*
X522835D03*
X565355Y29134D03*
X551181D03*
X537008D03*
X522835D03*
X565355Y20473D03*
X551181D03*
X537008D03*
X522835D03*
X565355Y14961D03*
X551181D03*
X537008D03*
X522835D03*
X586614Y48426D03*
Y34252D03*
Y20079D03*
Y44095D03*
Y38583D03*
Y29922D03*
Y24410D03*
Y15748D03*
Y10237D03*
Y5906D03*
X579528Y38977D03*
Y24804D03*
Y53150D03*
Y48819D03*
Y43307D03*
Y34646D03*
Y29134D03*
Y20473D03*
Y14961D03*
X758267Y48426D03*
X744094D03*
X729921D03*
X715748D03*
X758267Y44095D03*
X744094D03*
X729921D03*
X715748D03*
X758267Y38583D03*
X744094D03*
X729921D03*
X715748D03*
X758267Y34252D03*
X744094D03*
X729921D03*
X715748D03*
X758267Y29922D03*
X744094D03*
X729921D03*
X715748D03*
X758267Y24410D03*
X744094D03*
X729921D03*
X715748D03*
X758267Y20079D03*
X744094D03*
X729921D03*
X715748D03*
X758267Y15748D03*
X744094D03*
X729921D03*
X715748D03*
X758267Y10237D03*
X744094D03*
X729921D03*
X715748D03*
X758267Y5906D03*
X744094D03*
X729921D03*
X715748D03*
X751181Y53150D03*
X737007D03*
X722834D03*
X708661D03*
X751181Y48819D03*
X737007D03*
X722834D03*
X708661D03*
X751181Y43307D03*
X737007D03*
X722834D03*
X708661D03*
X751181Y38977D03*
X737007D03*
X722834D03*
X708661D03*
X751181Y34646D03*
X737007D03*
X722834D03*
X708661D03*
X751181Y29134D03*
X737007D03*
X722834D03*
X708661D03*
X751181Y24804D03*
X737007D03*
X722834D03*
X708661D03*
X751181Y20473D03*
X737007D03*
X722834D03*
X708661D03*
X751181Y14961D03*
X737007D03*
X722834D03*
X708661D03*
G54D56*
X377683Y314895D03*
X399258Y262952D03*
X429389Y267240D03*
X409550Y330250D03*
X436786Y351341D03*
X408020Y335630D03*
X498500Y194800D03*
X486644Y354873D03*
X478400Y367500D03*
Y363400D03*
X495100Y368350D03*
X542295Y480090D03*
X570633Y476488D03*
X566539Y461261D03*
X654313Y166929D03*
X684800Y210200D03*
X669500Y288000D03*
X678789Y268500D03*
X759170Y81900D03*
X759140Y77810D03*
X759170Y86100D03*
X736879Y155899D03*
X712646Y276558D03*
G54D74*
X658500Y371250D03*
G54D47*
X380500Y173000D03*
Y175200D03*
X382700Y173000D03*
Y175200D03*
X386500Y173000D03*
Y175200D03*
X388700Y173000D03*
Y175200D03*
X392500Y173000D03*
Y175200D03*
X394700Y173000D03*
Y175200D03*
X398500Y173000D03*
Y175200D03*
X400700Y173000D03*
Y175200D03*
X404500Y173000D03*
Y175200D03*
X406700Y173000D03*
Y175200D03*
X412700Y173000D03*
Y175200D03*
X410500Y173000D03*
Y175200D03*
X416500Y173000D03*
Y175200D03*
X418700Y173000D03*
Y175200D03*
X422500Y173000D03*
Y175200D03*
X428500Y173000D03*
Y175200D03*
X424700Y173000D03*
Y175200D03*
X430700Y173000D03*
Y175200D03*
X434500Y173000D03*
Y175200D03*
X436700Y173000D03*
Y175200D03*
X440500Y173000D03*
Y175200D03*
X442700Y173000D03*
Y175200D03*
X446500Y173000D03*
Y175200D03*
X448700Y173000D03*
Y175200D03*
X423297Y257900D03*
Y260100D03*
X407500Y253900D03*
Y256100D03*
X419300Y257900D03*
Y260100D03*
X411400Y253900D03*
Y256100D03*
X442500Y276000D03*
Y278200D03*
X440000Y276000D03*
Y278200D03*
X447500Y276000D03*
Y278200D03*
X452500Y173000D03*
Y175200D03*
X454700Y173000D03*
Y175200D03*
X458500Y173000D03*
Y175200D03*
X460700Y173000D03*
Y175200D03*
X464500Y173000D03*
Y175200D03*
X466700Y173000D03*
Y175200D03*
X470500Y173000D03*
Y175200D03*
X472700Y173000D03*
Y175200D03*
X478100Y154300D03*
Y156500D03*
X480400Y154300D03*
Y156500D03*
X485100Y154300D03*
Y156500D03*
X487400Y154300D03*
Y156500D03*
X492100Y154300D03*
Y156500D03*
X494400Y154300D03*
Y156500D03*
X499500Y154300D03*
Y156500D03*
X501800Y154300D03*
Y156500D03*
X504800Y159800D03*
Y162000D03*
X507100Y159800D03*
Y162000D03*
X451500Y209400D03*
Y211600D03*
X494100Y289600D03*
Y291800D03*
X486250Y285250D03*
Y287450D03*
X466658Y276174D03*
Y278374D03*
X468968Y276174D03*
Y278374D03*
X462553Y275970D03*
Y278170D03*
X474500Y299900D03*
X458700Y298100D03*
X462600Y298200D03*
X454700Y276000D03*
Y278200D03*
X458700Y276000D03*
Y278200D03*
X450000Y276000D03*
Y278200D03*
X458667Y315905D03*
Y318105D03*
X486308Y316042D03*
Y318242D03*
X451100Y315700D03*
Y317900D03*
X474500Y302100D03*
X458700Y300300D03*
X462600Y300400D03*
X515055Y173622D03*
Y175822D03*
X517255Y173622D03*
Y175822D03*
X524700Y173700D03*
X526900D03*
X533093Y220867D03*
Y223067D03*
X530893Y220867D03*
Y223067D03*
X524700Y175900D03*
X526900D03*
X534120Y240257D03*
Y242457D03*
X531920Y240257D03*
Y242457D03*
X512700Y317400D03*
Y319600D03*
X677505Y112037D03*
X667843Y170060D03*
Y172260D03*
X680671Y133232D03*
Y135432D03*
X673887Y133186D03*
Y135386D03*
X677505Y114237D03*
X686636Y133246D03*
Y135446D03*
X671452Y200715D03*
Y202915D03*
X699245Y111675D03*
Y113875D03*
G54D29*
X254300Y363700D03*
X300500Y138700D03*
X301000Y223200D03*
X300500Y180700D03*
X362810Y249340D03*
X362868Y277487D03*
X362677Y305262D03*
X581500Y459200D03*
X676531Y379833D03*
X788107Y122593D03*
G54D38*
X287500Y289700D03*
X358298Y253844D03*
X358342Y281987D03*
X358214Y310062D03*
X409100Y344000D03*
X421500Y344500D03*
X440740Y344644D03*
X435200Y334000D03*
X427500Y334100D03*
X421500Y334200D03*
X396000Y344100D03*
X467900Y354200D03*
X474577Y342865D03*
X496100Y355300D03*
X497206Y345231D03*
X464000Y344200D03*
X460000D03*
X451300Y344300D03*
X491445Y350358D03*
X477400Y354300D03*
X468000Y344200D03*
X486873Y350356D03*
X472000Y354200D03*
X482618Y342842D03*
X513517Y345246D03*
X521522D03*
X517517D03*
X518500Y355700D03*
X522500D03*
X549400Y489390D03*
X631500Y108700D03*
X632300Y158100D03*
X644710Y26267D03*
X637003Y65709D03*
X689468Y250105D03*
X691887Y267877D03*
X657031Y380083D03*
X666031D03*
X661531D03*
X698541Y202589D03*
X785350Y95200D03*
X781000D03*
X802696Y140800D03*
X786500D03*
X790500D03*
X796110Y186300D03*
X792000Y232700D03*
G54D65*
X555355Y470540D03*
X562855Y474415D03*
Y466665D03*
X555550Y484900D03*
X563050Y481025D03*
Y488775D03*
X791750Y78500D03*
X799250Y82375D03*
Y74625D03*
G54D66*
X529450Y485100D03*
X521950Y481225D03*
Y488975D03*
X757650Y91855D03*
Y99605D03*
X765150Y95730D03*
G54D48*
X374015Y156220D03*
X531496Y371299D03*
X596456Y116142D03*
X781496Y198818D03*
G54D75*
X724380Y291446D03*
Y289476D03*
Y287511D03*
Y285541D03*
Y283571D03*
Y281601D03*
Y279636D03*
Y277666D03*
Y275696D03*
Y273731D03*
Y271761D03*
Y269791D03*
Y267826D03*
Y265856D03*
Y263886D03*
Y261916D03*
Y259951D03*
Y257981D03*
Y256011D03*
Y254046D03*
Y252076D03*
Y250106D03*
Y248141D03*
Y246171D03*
Y244201D03*
Y242231D03*
Y240266D03*
Y238296D03*
X800080D03*
Y240266D03*
Y242231D03*
Y244201D03*
Y246171D03*
Y248141D03*
Y250106D03*
Y252076D03*
Y254046D03*
Y256011D03*
Y257981D03*
Y259951D03*
Y261916D03*
Y263886D03*
Y265856D03*
Y267826D03*
Y269791D03*
Y271761D03*
Y273731D03*
Y275696D03*
Y277666D03*
Y279636D03*
Y281601D03*
Y283571D03*
Y285541D03*
Y287511D03*
Y289476D03*
Y291446D03*
G54D39*
X287500Y286300D03*
X358298Y250444D03*
X358342Y278587D03*
X358214Y306662D03*
X409100Y340600D03*
X421500Y341100D03*
X440740Y341244D03*
X435200Y330600D03*
X427500Y330700D03*
X421500Y330800D03*
X396000Y340700D03*
X467900Y350800D03*
X474577Y339465D03*
X496100Y351900D03*
X497206Y341831D03*
X464000Y340800D03*
X460000D03*
X451300Y340900D03*
X491445Y346958D03*
X477400Y350900D03*
X468000Y340800D03*
X486873Y346956D03*
X472000Y350800D03*
X482618Y339442D03*
X513517Y341846D03*
X521522D03*
X517517D03*
X518500Y352300D03*
X522500D03*
X549400Y485990D03*
X631500Y105300D03*
X632300Y154700D03*
X644710Y22867D03*
X637003Y62309D03*
X689468Y246705D03*
X691887Y264477D03*
X657031Y376683D03*
X666031D03*
X661531D03*
X698541Y199189D03*
X785350Y91800D03*
X781000D03*
X802696Y137400D03*
X786500D03*
X790500D03*
X796110Y182900D03*
X792000Y229300D03*
G54D57*
X371648Y335023D03*
X427166Y297245D03*
X431102Y293307D03*
X442908Y293298D03*
X419292Y297245D03*
X423221Y293300D03*
X423228Y305118D03*
X431102Y301181D03*
X423229Y320867D03*
X431105Y309010D03*
X419291Y309055D03*
X442913Y305118D03*
X438976Y301181D03*
Y309055D03*
X434000Y322200D03*
X503468Y324325D03*
X497550Y324150D03*
X496000Y336000D03*
X506700Y336200D03*
X501400Y336000D03*
X468500Y333500D03*
X472600Y310400D03*
X466535Y305118D03*
X557500Y343350D03*
X552100Y343300D03*
X524500Y335500D03*
X516194Y332572D03*
X631700Y198500D03*
X626400D03*
X650936Y160874D03*
X656878Y161079D03*
X695770Y125429D03*
X693674Y132295D03*
X648035Y154330D03*
X642300Y198500D03*
X637000D03*
X646004Y179768D03*
X650722Y183439D03*
X646000Y185900D03*
X694087Y201724D03*
X690207Y205597D03*
X657113Y198415D03*
X651722Y198588D03*
X734500Y113400D03*
X737100Y103000D03*
X730200Y98200D03*
X719500Y102900D03*
X742700Y103100D03*
X739900Y112500D03*
X745700Y108700D03*
X724200Y110700D03*
X719000Y112700D03*
X715100Y107300D03*
X708300Y113300D03*
X725600Y103600D03*
X713700Y112500D03*
X724600Y97100D03*
X717087Y97384D03*
X703600Y110600D03*
X729400Y111800D03*
X734500Y139200D03*
X743400Y139100D03*
X738000Y133900D03*
X746400Y134600D03*
X736730Y166522D03*
X733372Y130235D03*
X742700Y130600D03*
X736800Y125200D03*
X733600Y120500D03*
X738200Y117600D03*
X741500Y146500D03*
X747700Y114800D03*
X747200Y127400D03*
X744222Y120527D03*
X716040Y176322D03*
X699999Y132427D03*
X727700Y118000D03*
X707861Y133930D03*
X752500Y127500D03*
X733792Y175376D03*
X733500Y146000D03*
X721500Y202600D03*
X710687Y202564D03*
X726032Y205904D03*
X736078Y181764D03*
X745659Y183788D03*
X746691Y189552D03*
X734043Y187231D03*
X745778Y178204D03*
X742978Y206202D03*
X715300Y214400D03*
G54D67*
X532812Y444771D03*
X537812D03*
X542812D03*
X547812D03*
Y464771D03*
X542812D03*
X537812D03*
X532812D03*
X800000Y172000D03*
X795000D03*
X790000D03*
X785000D03*
Y152000D03*
X790000D03*
X795000D03*
X800000D03*
G54D76*
X713712Y470871D03*
Y465871D03*
Y460871D03*
Y455871D03*
X733712D03*
Y460871D03*
Y465871D03*
Y470871D03*
G54D58*
X358550Y319900D03*
X354800D03*
X351050D03*
Y330500D03*
X354800D03*
X358550D03*
X674989Y255684D03*
X678739D03*
X682489D03*
Y245084D03*
X678739D03*
X674989D03*
G54D49*
X378811Y198292D03*
X381011D03*
X378811Y200592D03*
X381011D03*
X378811Y203792D03*
X381011D03*
X378811Y206092D03*
X381011D03*
X378811Y211592D03*
X381011D03*
X378811Y209292D03*
X381011D03*
X378811Y214792D03*
X381011D03*
X378811Y217092D03*
X381011D03*
X399400Y226400D03*
X401600D03*
X445568Y297155D03*
X447768D03*
X489050Y210650D03*
X491250D03*
X508338Y233748D03*
X510538D03*
X508338Y214971D03*
X510538D03*
X508338Y225790D03*
X510538D03*
X508338Y217456D03*
X510538D03*
X489100Y229900D03*
X491300D03*
X489117Y234208D03*
X491317D03*
X489100Y227400D03*
X491300D03*
X508338Y231089D03*
X510538D03*
X508338Y223290D03*
X510538D03*
X489950Y285450D03*
X492150D03*
X489900Y273650D03*
X492100D03*
X489900Y265600D03*
X492100D03*
X489950Y277500D03*
X492150D03*
X489050Y238200D03*
X491250D03*
X692612Y164865D03*
X694812D03*
X692685Y156336D03*
X694885D03*
X692450Y168950D03*
X694650D03*
X692612Y162665D03*
X694812D03*
X692685Y158536D03*
X694885D03*
X692600Y150050D03*
X694800D03*
X692602Y145815D03*
X694802D03*
X692450Y171150D03*
X694650D03*
X692600Y152250D03*
X694800D03*
X670097Y129076D03*
X672297D03*
X657737Y194808D03*
X659937D03*
X701341Y81023D03*
X703541D03*
X701344Y83270D03*
X703544D03*
X712560Y83760D03*
X714760D03*
X712559Y85992D03*
X714759D03*
X698923Y164914D03*
X701123D03*
X698950Y152240D03*
X701150D03*
X705362Y164913D03*
X707562D03*
X725142Y145165D03*
X727342D03*
X725142Y151175D03*
X727342D03*
X725142Y157715D03*
X727342D03*
X723922Y126891D03*
X726122D03*
X725142Y170065D03*
X727342D03*
X705362Y162713D03*
X707562D03*
X705321Y158619D03*
X707521D03*
X705352Y150035D03*
X707552D03*
X698923Y162714D03*
X701123D03*
X698944Y158543D03*
X701144D03*
X698950Y150040D03*
X701150D03*
X698952Y145865D03*
X701152D03*
X705321Y156419D03*
X707521D03*
X698944Y156343D03*
X701144D03*
X705352Y152235D03*
X707552D03*
X725142Y176315D03*
X727342D03*
X725142Y189185D03*
X727342D03*
X725142Y182795D03*
X727342D03*
G54D59*
X366040Y320965D03*
X368600D03*
X371160D03*
Y329035D03*
X368600D03*
X366040D03*
G54D77*
X739680Y429140D03*
Y438140D03*
G54D68*
X622826Y238652D03*
X619226D03*
X644700Y131100D03*
X641100D03*
X657800Y234700D03*
X654200D03*
X723200Y119500D03*
X719600D03*
G54D78*
X780495Y517441D03*
G54D69*
X658116Y36660D03*
Y34100D03*
Y31540D03*
X651616D03*
Y36660D03*
G54D79*
G01X121778Y-377522D02*
X122652Y-376647D01*
X123307Y-375189D01*
X123744Y-373146D01*
X123307Y-371397D01*
X122434Y-370230D01*
X120905Y-369355D01*
X115010D01*
Y-386855D01*
X122215D01*
X123744Y-385689D01*
X124617Y-383938D01*
X125054Y-381897D01*
X124617Y-379855D01*
X123307Y-378105D01*
X121778Y-377522D01*
X115010D01*
G01X134475Y-386855D02*
Y-375189D01*
G01Y-377522D02*
X135567Y-376355D01*
X136659Y-375480D01*
X138187Y-375189D01*
X139278Y-375480D01*
X140589Y-376355D01*
G01X150447Y-392105D02*
X151757Y-392688D01*
X153504Y-392105D01*
X154595Y-390939D01*
X155469Y-389480D01*
X156778Y-384814D01*
X159617Y-375189D01*
G01X152630D02*
X156778Y-384814D01*
G01X176025Y-376647D02*
X174497Y-375480D01*
X173187Y-375189D01*
X171440Y-375772D01*
X170130Y-376938D01*
X169257Y-378980D01*
X169038Y-381022D01*
X169257Y-383064D01*
X170130Y-384814D01*
X171440Y-386272D01*
X173187Y-386855D01*
X174715Y-386272D01*
X176025Y-385105D01*
G01X186757Y-378980D02*
X193744D01*
X193089Y-376938D01*
X191997Y-375772D01*
X190469Y-375189D01*
X188940Y-375480D01*
X187630Y-376355D01*
X186757Y-378397D01*
X186320Y-380147D01*
Y-381897D01*
X186757Y-383647D01*
X187849Y-385397D01*
X189159Y-386563D01*
X190687Y-386855D01*
X192215Y-386272D01*
X193744Y-384522D01*
G01X229835Y-370814D02*
X228525Y-369938D01*
X226997Y-369355D01*
X225250D01*
X223285Y-370230D01*
X221757Y-371688D01*
X220665Y-373439D01*
X219792Y-376355D01*
X219573Y-378980D01*
X220010Y-381605D01*
X220665Y-383355D01*
X221975Y-385105D01*
X223504Y-386272D01*
X225032Y-386855D01*
X226560D01*
X228089Y-386272D01*
X229399Y-385397D01*
X230491Y-384231D01*
G01X246462Y-386855D02*
Y-375189D01*
G01Y-377230D02*
X245589Y-376064D01*
X244278Y-375480D01*
X242750Y-375189D01*
X241222Y-375772D01*
X239912Y-376938D01*
X239038Y-378688D01*
X238602Y-381022D01*
X239038Y-383355D01*
X239912Y-385105D01*
X241222Y-386272D01*
X242750Y-386855D01*
X244278Y-386563D01*
X245589Y-385689D01*
X246462Y-384522D01*
G01X256320Y-386855D02*
Y-375189D01*
G01Y-378105D02*
X257194Y-376647D01*
X258504Y-375480D01*
X260250Y-375189D01*
X261778Y-375480D01*
X263089Y-376647D01*
X263744Y-378688D01*
Y-386855D01*
G01X272947Y-392105D02*
X274257Y-392688D01*
X276004Y-392105D01*
X277095Y-390939D01*
X277969Y-389480D01*
X279278Y-384814D01*
X282117Y-375189D01*
G01X275130D02*
X279278Y-384814D01*
G01X295032Y-386855D02*
X293722Y-386563D01*
X292412Y-385397D01*
X291538Y-383355D01*
X291102Y-381022D01*
X291538Y-378688D01*
X292412Y-376647D01*
X293722Y-375480D01*
X295032Y-375189D01*
X296342Y-375480D01*
X297652Y-376647D01*
X298525Y-378688D01*
X298744Y-381022D01*
X298525Y-383355D01*
X297652Y-385397D01*
X296342Y-386563D01*
X295032Y-386855D01*
G01X308820D02*
Y-375189D01*
G01Y-378105D02*
X309694Y-376647D01*
X311004Y-375480D01*
X312750Y-375189D01*
X314278Y-375480D01*
X315589Y-376647D01*
X316244Y-378688D01*
Y-386855D01*
G01X342947Y-384522D02*
X344694Y-385980D01*
X346659Y-386855D01*
X348405D01*
X350152Y-385980D01*
X351462Y-384522D01*
X352117Y-382480D01*
X351680Y-380439D01*
X350589Y-378688D01*
X348624Y-377522D01*
X346004Y-376938D01*
X344475Y-375772D01*
X343820Y-373730D01*
X344257Y-371688D01*
X345349Y-370230D01*
X346877Y-369355D01*
X348405D01*
X349934Y-369938D01*
X351244Y-371397D01*
G01X369835Y-370814D02*
X368525Y-369938D01*
X366997Y-369355D01*
X365250D01*
X363285Y-370230D01*
X361757Y-371688D01*
X360665Y-373439D01*
X359792Y-376355D01*
X359573Y-378980D01*
X360010Y-381605D01*
X360665Y-383355D01*
X361975Y-385105D01*
X363504Y-386272D01*
X365032Y-386855D01*
X366560D01*
X368089Y-386272D01*
X369399Y-385397D01*
X370491Y-384231D01*
G01X387335Y-370814D02*
X386025Y-369938D01*
X384497Y-369355D01*
X382750D01*
X380785Y-370230D01*
X379257Y-371688D01*
X378165Y-373439D01*
X377292Y-376355D01*
X377073Y-378980D01*
X377510Y-381605D01*
X378165Y-383355D01*
X379475Y-385105D01*
X381004Y-386272D01*
X382532Y-386855D01*
X384060D01*
X385589Y-386272D01*
X386899Y-385397D01*
X387991Y-384231D01*
G01X210605Y-341855D02*
Y-324355D01*
X216282Y-338938D01*
X221959Y-324355D01*
Y-341855D01*
G01X233782D02*
X232472Y-341563D01*
X231162Y-340397D01*
X230288Y-338355D01*
X229852Y-336022D01*
X230288Y-333688D01*
X231162Y-331647D01*
X232472Y-330480D01*
X233782Y-330189D01*
X235092Y-330480D01*
X236402Y-331647D01*
X237275Y-333688D01*
X237494Y-336022D01*
X237275Y-338355D01*
X236402Y-340397D01*
X235092Y-341563D01*
X233782Y-341855D01*
G01X255212Y-324355D02*
Y-341855D01*
G01Y-339231D02*
X254339Y-340689D01*
X253028Y-341563D01*
X251500Y-341855D01*
X249754Y-341272D01*
X248444Y-339814D01*
X247570Y-338064D01*
X247352Y-336022D01*
X247570Y-333980D01*
X248444Y-332230D01*
X249754Y-330772D01*
X251500Y-330189D01*
X253028Y-330480D01*
X254120Y-331064D01*
X255212Y-332230D01*
G01X265507Y-333980D02*
X272494D01*
X271839Y-331938D01*
X270747Y-330772D01*
X269219Y-330189D01*
X267690Y-330480D01*
X266380Y-331355D01*
X265507Y-333397D01*
X265070Y-335147D01*
Y-336897D01*
X265507Y-338647D01*
X266599Y-340397D01*
X267909Y-341563D01*
X269437Y-341855D01*
X270965Y-341272D01*
X272494Y-339522D01*
G01X286282Y-341855D02*
Y-324355D01*
G01X566882Y-386855D02*
Y-369355D01*
X564262Y-372855D01*
G01Y-386855D02*
X569502D01*
G01X580234Y-379564D02*
X581762Y-377522D01*
X583072Y-376355D01*
X584819Y-375772D01*
X586347Y-376355D01*
X587439Y-377522D01*
X588312Y-379272D01*
X588530Y-381313D01*
X588312Y-383064D01*
X587439Y-384814D01*
X586128Y-386272D01*
X584600Y-386855D01*
X582854Y-386272D01*
X581325Y-384522D01*
X580452Y-381897D01*
X580234Y-378980D01*
X580670Y-375189D01*
X581325Y-373146D01*
X582417Y-371105D01*
X583945Y-369647D01*
X585474Y-369355D01*
X587002Y-369938D01*
X588094Y-371397D01*
G01X597079Y-383355D02*
X598388Y-385397D01*
X600135Y-386563D01*
X602100Y-386855D01*
X603847Y-386563D01*
X605594Y-385105D01*
X606685Y-383355D01*
X606904Y-381605D01*
X606467Y-379564D01*
X604939Y-378105D01*
X603410Y-377522D01*
X601445D01*
G01X603410D02*
X604720Y-376647D01*
X605812Y-375189D01*
X606249Y-373439D01*
X605812Y-371688D01*
X604720Y-370230D01*
X602755Y-369355D01*
X600790Y-369647D01*
X598825Y-370814D01*
G01X619382Y-386855D02*
Y-369355D01*
X616762Y-372855D01*
G01Y-386855D02*
X622002D01*
G01X632734Y-379564D02*
X634262Y-377522D01*
X635572Y-376355D01*
X637319Y-375772D01*
X638847Y-376355D01*
X639939Y-377522D01*
X640812Y-379272D01*
X641030Y-381313D01*
X640812Y-383064D01*
X639939Y-384814D01*
X638628Y-386272D01*
X637100Y-386855D01*
X635354Y-386272D01*
X633825Y-384522D01*
X632952Y-381897D01*
X632734Y-378980D01*
X633170Y-375189D01*
X633825Y-373146D01*
X634917Y-371105D01*
X636445Y-369647D01*
X637974Y-369355D01*
X639502Y-369938D01*
X640594Y-371397D01*
G01X553765Y-341855D02*
Y-324355D01*
X559005D01*
X560752Y-325230D01*
X562062Y-327272D01*
X562499Y-329605D01*
X562062Y-331938D01*
X560970Y-333688D01*
X559005Y-334564D01*
X553765D01*
G01X580435Y-325814D02*
X579125Y-324938D01*
X577597Y-324355D01*
X575850D01*
X573885Y-325230D01*
X572357Y-326688D01*
X571265Y-328439D01*
X570392Y-331355D01*
X570173Y-333980D01*
X570610Y-336605D01*
X571265Y-338355D01*
X572575Y-340105D01*
X574104Y-341272D01*
X575632Y-341855D01*
X577160D01*
X578689Y-341272D01*
X579999Y-340397D01*
X581091Y-339231D01*
G01X594878Y-332522D02*
X595752Y-331647D01*
X596407Y-330189D01*
X596844Y-328146D01*
X596407Y-326397D01*
X595534Y-325230D01*
X594005Y-324355D01*
X588110D01*
Y-341855D01*
X595315D01*
X596844Y-340689D01*
X597717Y-338938D01*
X598154Y-336897D01*
X597717Y-334855D01*
X596407Y-333105D01*
X594878Y-332522D01*
X588110D01*
G01X604082Y-347688D02*
X617182D01*
G01X623110Y-341855D02*
Y-324355D01*
X633154Y-341855D01*
Y-324355D01*
G01X645632Y-341855D02*
X643885Y-341563D01*
X642357Y-340397D01*
X641047Y-338647D01*
X640173Y-336605D01*
X639737Y-334272D01*
Y-331938D01*
X640173Y-329605D01*
X641047Y-327563D01*
X642357Y-325814D01*
X643885Y-324647D01*
X645632Y-324355D01*
X647378Y-324647D01*
X648907Y-325814D01*
X650217Y-327563D01*
X651091Y-329605D01*
X651527Y-331938D01*
Y-334272D01*
X651091Y-336605D01*
X650217Y-338647D01*
X648907Y-340397D01*
X647378Y-341563D01*
X645632Y-341855D01*
G01X696473Y-324355D02*
X701932Y-341855D01*
X707391Y-324355D01*
G01X723799Y-341855D02*
X715065D01*
Y-324355D01*
X723799D01*
G01X720305Y-332813D02*
X715065D01*
G01X732565Y-341855D02*
Y-324355D01*
X738024D01*
X739770Y-325230D01*
X740862Y-326397D01*
X741299Y-328730D01*
X740862Y-331064D01*
X739552Y-332522D01*
X738024Y-333397D01*
X732565D01*
G01X738024D02*
X741299Y-341855D01*
G01X754432Y-342438D02*
X753995Y-342147D01*
Y-341563D01*
X754432Y-341272D01*
X754869Y-341563D01*
Y-342147D01*
X754432Y-342438D01*
G01X728182Y-386855D02*
Y-369355D01*
X725562Y-372855D01*
G01Y-386855D02*
X730802D01*
G01X902636Y-377522D02*
X901762Y-376647D01*
X901107Y-375189D01*
X900670Y-373146D01*
X901107Y-371397D01*
X901980Y-370230D01*
X903509Y-369355D01*
X909404D01*
Y-386855D01*
X902199D01*
X900670Y-385689D01*
X899797Y-383938D01*
X899360Y-381897D01*
X899797Y-379855D01*
X901107Y-378105D01*
X902636Y-377522D01*
X909404D01*
G01X892559Y-386855D02*
Y-369355D01*
X886882Y-383938D01*
X881205Y-369355D01*
Y-386855D01*
G01X874841D02*
X869382Y-369355D01*
X863923Y-386855D01*
G01X865889Y-380730D02*
X872876D01*
G01X856467Y-384522D02*
X854720Y-385980D01*
X852755Y-386855D01*
X851009D01*
X849262Y-385980D01*
X847952Y-384522D01*
X847297Y-382480D01*
X847734Y-380439D01*
X848825Y-378688D01*
X850790Y-377522D01*
X853410Y-376938D01*
X854939Y-375772D01*
X855594Y-373730D01*
X855157Y-371688D01*
X854065Y-370230D01*
X852537Y-369355D01*
X851009D01*
X849480Y-369938D01*
X848170Y-371397D01*
G01X839185Y-386855D02*
Y-369355D01*
G01X830889D02*
X839185Y-380147D01*
G01X829579Y-386855D02*
X835474Y-375189D01*
G01X830015Y-324355D02*
Y-341855D01*
X838749D01*
G01X855812D02*
Y-330189D01*
G01Y-332230D02*
X854939Y-331064D01*
X853628Y-330480D01*
X852100Y-330189D01*
X850572Y-330772D01*
X849262Y-331938D01*
X848388Y-333688D01*
X847952Y-336022D01*
X848388Y-338355D01*
X849262Y-340105D01*
X850572Y-341272D01*
X852100Y-341855D01*
X853628Y-341563D01*
X854939Y-340689D01*
X855812Y-339522D01*
G01X864797Y-347105D02*
X866107Y-347688D01*
X867854Y-347105D01*
X868945Y-345939D01*
X869819Y-344480D01*
X871128Y-339814D01*
X873967Y-330189D01*
G01X866980D02*
X871128Y-339814D01*
G01X883607Y-333980D02*
X890594D01*
X889939Y-331938D01*
X888847Y-330772D01*
X887319Y-330189D01*
X885790Y-330480D01*
X884480Y-331355D01*
X883607Y-333397D01*
X883170Y-335147D01*
Y-336897D01*
X883607Y-338647D01*
X884699Y-340397D01*
X886009Y-341563D01*
X887537Y-341855D01*
X889065Y-341272D01*
X890594Y-339522D01*
G01X901325Y-341855D02*
Y-330189D01*
G01Y-332522D02*
X902417Y-331355D01*
X903509Y-330480D01*
X905037Y-330189D01*
X906128Y-330480D01*
X907439Y-331355D01*
G01X994432Y-386855D02*
X992685Y-386563D01*
X991157Y-385397D01*
X989847Y-383647D01*
X988973Y-381605D01*
X988537Y-379272D01*
Y-376938D01*
X988973Y-374605D01*
X989847Y-372563D01*
X991157Y-370814D01*
X992685Y-369647D01*
X994432Y-369355D01*
X996178Y-369647D01*
X997707Y-370814D01*
X999017Y-372563D01*
X999891Y-374605D01*
X1000327Y-376938D01*
Y-379272D01*
X999891Y-381605D01*
X999017Y-383647D01*
X997707Y-385397D01*
X996178Y-386563D01*
X994432Y-386855D01*
G01X996178Y-382188D02*
X998799Y-386855D01*
G01X1007129Y-369355D02*
Y-381897D01*
X1008002Y-384522D01*
X1009749Y-386272D01*
X1011932Y-386855D01*
X1014115Y-386272D01*
X1015862Y-384522D01*
X1016735Y-381897D01*
Y-369355D01*
G01X1026812D02*
X1032052D01*
G01X1029432D02*
Y-386855D01*
G01X1026812D02*
X1032052D01*
G01X1041910D02*
Y-369355D01*
X1051954Y-386855D01*
Y-369355D01*
G01X1069235Y-370814D02*
X1067925Y-369938D01*
X1066397Y-369355D01*
X1064650D01*
X1062685Y-370230D01*
X1061157Y-371688D01*
X1060065Y-373439D01*
X1059192Y-376355D01*
X1058973Y-378980D01*
X1059410Y-381605D01*
X1060065Y-383355D01*
X1061375Y-385105D01*
X1062904Y-386272D01*
X1064432Y-386855D01*
X1065960D01*
X1067489Y-386272D01*
X1068799Y-385397D01*
X1069891Y-384231D01*
G01X1081932Y-386855D02*
Y-378980D01*
X1077565Y-369355D01*
G01X1086299D02*
X1081932Y-378980D01*
G01X972129Y-341855D02*
Y-324355D01*
X976495D01*
X978242Y-325230D01*
X979552Y-326397D01*
X980644Y-328146D01*
X981517Y-330189D01*
X981735Y-333105D01*
X981517Y-336022D01*
X980644Y-338064D01*
X979552Y-339814D01*
X978242Y-340980D01*
X976495Y-341855D01*
X972129D01*
G01X991157Y-333980D02*
X998144D01*
X997489Y-331938D01*
X996397Y-330772D01*
X994869Y-330189D01*
X993340Y-330480D01*
X992030Y-331355D01*
X991157Y-333397D01*
X990720Y-335147D01*
Y-336897D01*
X991157Y-338647D01*
X992249Y-340397D01*
X993559Y-341563D01*
X995087Y-341855D01*
X996615Y-341272D01*
X998144Y-339522D01*
G01X1008657Y-339814D02*
X1009749Y-340980D01*
X1011277Y-341855D01*
X1012587D01*
X1013897Y-341272D01*
X1014770Y-340397D01*
X1015207Y-339231D01*
X1014989Y-337480D01*
X1014115Y-336605D01*
X1010185Y-334855D01*
X1009312Y-332813D01*
X1009749Y-331355D01*
X1010622Y-330480D01*
X1011932Y-330189D01*
X1013242Y-330480D01*
X1014552Y-331355D01*
G01X1029432Y-330189D02*
Y-341855D01*
G01Y-325522D02*
X1028995Y-325230D01*
Y-324647D01*
X1029432Y-324355D01*
X1029869Y-324647D01*
Y-325230D01*
X1029432Y-325522D01*
G01X1043875Y-346230D02*
X1045404Y-347397D01*
X1047150Y-347688D01*
X1048678Y-347397D01*
X1049989Y-345939D01*
X1050862Y-343897D01*
Y-330189D01*
G01Y-332522D02*
X1049989Y-331355D01*
X1048678Y-330480D01*
X1047150Y-330189D01*
X1045404Y-330772D01*
X1044312Y-331938D01*
X1043438Y-333980D01*
X1043002Y-336022D01*
X1043220Y-337772D01*
X1044094Y-339814D01*
X1045404Y-341272D01*
X1047150Y-341855D01*
X1048460Y-341563D01*
X1049989Y-340397D01*
X1050862Y-339231D01*
G01X1060720Y-341855D02*
Y-330189D01*
G01Y-333105D02*
X1061594Y-331647D01*
X1062904Y-330480D01*
X1064650Y-330189D01*
X1066178Y-330480D01*
X1067489Y-331647D01*
X1068144Y-333688D01*
Y-341855D01*
G01X1078657Y-333980D02*
X1085644D01*
X1084989Y-331938D01*
X1083897Y-330772D01*
X1082369Y-330189D01*
X1080840Y-330480D01*
X1079530Y-331355D01*
X1078657Y-333397D01*
X1078220Y-335147D01*
Y-336897D01*
X1078657Y-338647D01*
X1079749Y-340397D01*
X1081059Y-341563D01*
X1082587Y-341855D01*
X1084115Y-341272D01*
X1085644Y-339522D01*
G01X1096375Y-341855D02*
Y-330189D01*
G01Y-332522D02*
X1097467Y-331355D01*
X1098559Y-330480D01*
X1100087Y-330189D01*
X1101178Y-330480D01*
X1102489Y-331355D01*
G01X1143132Y-369355D02*
X1141385Y-369938D01*
X1140075Y-371397D01*
X1139202Y-373146D01*
X1138547Y-375480D01*
X1138329Y-378105D01*
X1138547Y-380730D01*
X1139202Y-383064D01*
X1140075Y-384814D01*
X1141385Y-386272D01*
X1143132Y-386855D01*
X1144878Y-386272D01*
X1146189Y-384814D01*
X1147062Y-383064D01*
X1147717Y-380730D01*
X1147935Y-378105D01*
X1147717Y-375480D01*
X1147062Y-373146D01*
X1146189Y-371397D01*
X1144878Y-369938D01*
X1143132Y-369355D01*
G01X1156484Y-379564D02*
X1158012Y-377522D01*
X1159322Y-376355D01*
X1161069Y-375772D01*
X1162597Y-376355D01*
X1163689Y-377522D01*
X1164562Y-379272D01*
X1164780Y-381313D01*
X1164562Y-383064D01*
X1163689Y-384814D01*
X1162378Y-386272D01*
X1160850Y-386855D01*
X1159104Y-386272D01*
X1157575Y-384522D01*
X1156702Y-381897D01*
X1156484Y-378980D01*
X1156920Y-375189D01*
X1157575Y-373146D01*
X1158667Y-371105D01*
X1160195Y-369647D01*
X1161724Y-369355D01*
X1163252Y-369938D01*
X1164344Y-371397D01*
G01X1174202Y-387438D02*
X1182062Y-369355D01*
G01X1191484Y-372272D02*
X1192794Y-370522D01*
X1194322Y-369647D01*
X1196069Y-369355D01*
X1198252Y-369938D01*
X1199780Y-371397D01*
X1200217Y-373146D01*
X1199999Y-374897D01*
X1199125Y-376355D01*
X1194759Y-379272D01*
X1192794Y-381313D01*
X1191484Y-384231D01*
X1191047Y-386855D01*
X1200217D01*
G01X1213132D02*
Y-369355D01*
X1210512Y-372855D01*
G01Y-386855D02*
X1215752D01*
G01X1226702Y-387438D02*
X1234562Y-369355D01*
G01X1243984Y-372272D02*
X1245294Y-370522D01*
X1246822Y-369647D01*
X1248569Y-369355D01*
X1250752Y-369938D01*
X1252280Y-371397D01*
X1252717Y-373146D01*
X1252499Y-374897D01*
X1251625Y-376355D01*
X1247259Y-379272D01*
X1245294Y-381313D01*
X1243984Y-384231D01*
X1243547Y-386855D01*
X1252717D01*
G01X1265632Y-369355D02*
X1263885Y-369938D01*
X1262575Y-371397D01*
X1261702Y-373146D01*
X1261047Y-375480D01*
X1260829Y-378105D01*
X1261047Y-380730D01*
X1261702Y-383064D01*
X1262575Y-384814D01*
X1263885Y-386272D01*
X1265632Y-386855D01*
X1267378Y-386272D01*
X1268689Y-384814D01*
X1269562Y-383064D01*
X1270217Y-380730D01*
X1270435Y-378105D01*
X1270217Y-375480D01*
X1269562Y-373146D01*
X1268689Y-371397D01*
X1267378Y-369938D01*
X1265632Y-369355D01*
G01X1283132Y-386855D02*
Y-369355D01*
X1280512Y-372855D01*
G01Y-386855D02*
X1285752D01*
G01X1300195D02*
X1300632Y-383064D01*
X1301287Y-379855D01*
X1302160Y-376938D01*
X1303252Y-373730D01*
X1304999Y-369355D01*
X1296265D01*
G01X1190829Y-341855D02*
Y-324355D01*
X1195195D01*
X1196942Y-325230D01*
X1198252Y-326397D01*
X1199344Y-328146D01*
X1200217Y-330189D01*
X1200435Y-333105D01*
X1200217Y-336022D01*
X1199344Y-338064D01*
X1198252Y-339814D01*
X1196942Y-340980D01*
X1195195Y-341855D01*
X1190829D01*
G01X1217062D02*
Y-330189D01*
G01Y-332230D02*
X1216189Y-331064D01*
X1214878Y-330480D01*
X1213350Y-330189D01*
X1211822Y-330772D01*
X1210512Y-331938D01*
X1209638Y-333688D01*
X1209202Y-336022D01*
X1209638Y-338355D01*
X1210512Y-340105D01*
X1211822Y-341272D01*
X1213350Y-341855D01*
X1214878Y-341563D01*
X1216189Y-340689D01*
X1217062Y-339522D01*
G01X1230632Y-324355D02*
Y-341855D01*
G01X1227575Y-330189D02*
X1233689D01*
G01X1244857Y-333980D02*
X1251844D01*
X1251189Y-331938D01*
X1250097Y-330772D01*
X1248569Y-330189D01*
X1247040Y-330480D01*
X1245730Y-331355D01*
X1244857Y-333397D01*
X1244420Y-335147D01*
Y-336897D01*
X1244857Y-338647D01*
X1245949Y-340397D01*
X1247259Y-341563D01*
X1248787Y-341855D01*
X1250315Y-341272D01*
X1251844Y-339522D01*
M02*
